G04 ================== begin FILE IDENTIFICATION RECORD ==================*
G04 Layout Name:  9049_F0T_FAN_BOARD_MP5048_D_v02_20221209_0830.brd*
G04 Film Name:    top.art*
G04 File Format:  Gerber RS274X*
G04 File Origin:  Cadence Allegro 17.2-S081*
G04 Origin Date:  Mon Dec 12 15:05:04 2022*
G04 *
G04 Layer:  DRAWING FORMAT/TITLE_BLOCK_A*
G04 Layer:  PIN/SPECIAL_DRILL*
G04 Layer:  DRAWING FORMAT/TITLE_BLOCK*
G04 Layer:  VIA CLASS/TOP*
G04 Layer:  PIN/TOP*
G04 Layer:  MANUFACTURING/PHOTOPLOT_OUTLINE*
G04 Layer:  ETCH/TOP*
G04 Layer:  DRAWING FORMAT/TITLE_DATA_TOP*
G04 *
G04 Offset:    (0.00 0.00)*
G04 Mirror:    No*
G04 Mode:      Positive*
G04 Rotation:  0*
G04 FullContactRelief:  No*
G04 UndefLineWidth:     6.00*
G04 ================== end FILE IDENTIFICATION RECORD ====================*
%FSLAX25Y25*MOIN*%
%IR0*IPPOS*OFA0.00000B0.00000*MIA0B0*SFA1.00000B1.00000*%
%AMMACRO33*
4,1,46,.05906,.17844,
.059724,.155545,
.06128,.13665,
.09787,-.20608,
.098198,-.223234,
.095542,-.240184,
.089983,-.256415,
.081691,-.271435,
.070916,-.284786,
.057986,-.296063,
.043294,-.304924,
.027287,-.311099,
.010451,-.314401,
-.006703,-.314729,
-.023653,-.312073,
-.039884,-.306514,
-.054904,-.298221,
-.068255,-.287446,
-.079532,-.274517,
-.088393,-.259825,
-.094568,-.243818,
-.09787,-.226982,
-.098198,-.209828,
-.09787,-.20608,
-.06128,.13665,
-.059515,.159487,
-.05906,.17844,
-.05906,.25591,
-.058163,.266166,
-.055498,.27611,
-.051147,.28544,
-.045243,.293873,
-.037963,.301153,
-.02953,.307057,
-.0202,.311408,
-.010256,.314073,
0.0,.31497,
.010256,.314073,
.0202,.311408,
.02953,.307057,
.037963,.301153,
.045243,.293873,
.051147,.28544,
.055498,.27611,
.058163,.266166,
.05906,.25591,
.05906,.17844,
0.0*
%
%ADD33MACRO33*%
%ADD12C,.02*%
%ADD46R,.032X.007*%
%ADD14C,.03*%
%ADD44R,.007X.032*%
%ADD48R,.032X.197*%
%ADD19C,.054*%
%ADD51C,.039*%
%ADD22R,.174X.087*%
%ADD11C,.085*%
%ADD18C,.059*%
%ADD20R,.054X.054*%
%AMMACRO27*
4,1,28,-.00748,-.00052,
-.00984,-.00052,
-.00984,-.00603,
-.009782,-.006705,
-.009607,-.007359,
-.009321,-.007974,
-.008933,-.008529,
-.008455,-.009009,
-.0079,-.009398,
-.007286,-.009685,
-.006632,-.009861,
-.005957,-.00992,
-.00591,-.00992,
.00591,-.00992,
.006585,-.009869,
.007242,-.009701,
.007859,-.009421,
.008418,-.009039,
.008903,-.008565,
.009297,-.008015,
.009591,-.007404,
.009773,-.006751,
.00984,-.006077,
.00984,-.00603,
.00984,-.00052,
.00748,-.00052,
.00748,.00991,
-.00748,.00991,
-.00748,-.00052,
0.0*
%
%ADD27MACRO27*%
%AMMACRO17*
4,1,28,-.00052,.00748,
-.00052,.00984,
-.00603,.00984,
-.006705,.009782,
-.007359,.009607,
-.007974,.009321,
-.008529,.008933,
-.009009,.008455,
-.009398,.0079,
-.009685,.007286,
-.009861,.006632,
-.00992,.005957,
-.00992,.00591,
-.00992,-.00591,
-.009869,-.006585,
-.009701,-.007242,
-.009421,-.007859,
-.009039,-.008418,
-.008565,-.008903,
-.008015,-.009297,
-.007404,-.009591,
-.006751,-.009773,
-.006077,-.00984,
-.00603,-.00984,
-.00052,-.00984,
-.00052,-.00748,
.00991,-.00748,
.00991,.00748,
-.00052,.00748,
0.0*
%
%ADD17MACRO17*%
%AMMACRO26*
4,1,28,-.00748,.00051,
-.00984,.00051,
-.00984,.00602,
-.009782,.006695,
-.009607,.007349,
-.009321,.007964,
-.008933,.008519,
-.008455,.008998,
-.0079,.009388,
-.007287,.009675,
-.006632,.009851,
-.005958,.00991,
-.00591,.00991,
.00591,.00991,
.006585,.009859,
.007242,.009691,
.007859,.009411,
.008418,.009029,
.008903,.008555,
.009297,.008005,
.00959,.007394,
.009773,.006742,
.00984,.006068,
.00984,.00602,
.00984,.00051,
.00748,.00051,
.00748,-.00992,
-.00748,-.00992,
-.00748,.00051,
0.0*
%
%ADD26MACRO26*%
%AMMACRO25*
4,1,28,.00051,.00748,
.00051,.00984,
.00602,.00984,
.006695,.009782,
.007349,.009607,
.007964,.009321,
.008519,.008933,
.008998,.008455,
.009388,.0079,
.009675,.007287,
.009851,.006632,
.00991,.005958,
.00991,.00591,
.00991,-.00591,
.009859,-.006585,
.009691,-.007242,
.009411,-.007859,
.009029,-.008418,
.008555,-.008903,
.008005,-.009297,
.007394,-.00959,
.006742,-.009773,
.006068,-.00984,
.00602,-.00984,
.00051,-.00984,
.00051,-.00748,
-.00992,-.00748,
-.00992,.00748,
.00051,.00748,
0.0*
%
%ADD25MACRO25*%
%ADD42R,.02X.016*%
%ADD21R,.05X.04*%
%ADD50R,.016X.02*%
%ADD47R,.024X.022*%
%ADD16R,.04X.05*%
%ADD40R,.032X.024*%
%ADD39R,.022X.024*%
%ADD29R,.036X.011*%
%ADD15R,.02X.018*%
%ADD37R,.024X.032*%
%ADD28R,.011X.036*%
%ADD13R,.018X.02*%
%ADD53C,.4*%
%ADD38R,.032X.034*%
%ADD43R,.032X.028*%
%ADD41R,.028X.032*%
%ADD10C,.125*%
%ADD36R,.068X.022*%
%ADD49R,.036X.028*%
%ADD35R,.059X.014*%
%ADD52R,.014X.059*%
%ADD54R,.173X.248*%
%ADD34O,.355X.827*%
%ADD45R,.107X.107*%
%ADD30R,.109X.109*%
%AMMACRO32*
4,1,28,.00748,.00052,
.00984,.00052,
.00984,.00603,
.009782,.006705,
.009607,.007359,
.009321,.007974,
.008933,.008529,
.008455,.009009,
.0079,.009398,
.007286,.009685,
.006632,.009861,
.005957,.00992,
.00591,.00992,
-.00591,.00992,
-.006585,.009869,
-.007242,.009701,
-.007859,.009421,
-.008418,.009039,
-.008903,.008565,
-.009297,.008015,
-.009591,.007404,
-.009773,.006751,
-.00984,.006077,
-.00984,.00603,
-.00984,.00052,
-.00748,.00052,
-.00748,-.00991,
.00748,-.00991,
.00748,.00052,
0.0*
%
%ADD32MACRO32*%
%AMMACRO24*
4,1,28,.00052,-.00748,
.00052,-.00984,
.00603,-.00984,
.006705,-.009782,
.007359,-.009607,
.007974,-.009321,
.008529,-.008933,
.009009,-.008455,
.009398,-.0079,
.009685,-.007286,
.009861,-.006632,
.00992,-.005957,
.00992,-.00591,
.00992,.00591,
.009869,.006585,
.009701,.007242,
.009421,.007859,
.009039,.008418,
.008565,.008903,
.008015,.009297,
.007404,.009591,
.006751,.009773,
.006077,.00984,
.00603,.00984,
.00052,.00984,
.00052,.00748,
-.00991,.00748,
-.00991,-.00748,
.00052,-.00748,
0.0*
%
%ADD24MACRO24*%
%AMMACRO31*
4,1,28,.00748,-.00051,
.00984,-.00051,
.00984,-.00602,
.009782,-.006695,
.009607,-.007349,
.009321,-.007964,
.008933,-.008519,
.008455,-.008998,
.0079,-.009388,
.007287,-.009675,
.006632,-.009851,
.005958,-.00991,
.00591,-.00991,
-.00591,-.00991,
-.006585,-.009859,
-.007242,-.009691,
-.007859,-.009411,
-.008418,-.009029,
-.008903,-.008555,
-.009297,-.008005,
-.00959,-.007394,
-.009773,-.006742,
-.00984,-.006068,
-.00984,-.00602,
-.00984,-.00051,
-.00748,-.00051,
-.00748,.00992,
.00748,.00992,
.00748,-.00051,
0.0*
%
%ADD31MACRO31*%
%AMMACRO23*
4,1,28,-.00051,-.00748,
-.00051,-.00984,
-.00602,-.00984,
-.006695,-.009782,
-.007349,-.009607,
-.007964,-.009321,
-.008519,-.008933,
-.008998,-.008455,
-.009388,-.0079,
-.009675,-.007287,
-.009851,-.006632,
-.00991,-.005958,
-.00991,-.00591,
-.00991,.00591,
-.009859,.006585,
-.009691,.007242,
-.009411,.007859,
-.009029,.008418,
-.008555,.008903,
-.008005,.009297,
-.007394,.00959,
-.006742,.009773,
-.006068,.00984,
-.00602,.00984,
-.00051,.00984,
-.00051,.00748,
.00992,.00748,
.00992,-.00748,
-.00051,-.00748,
0.0*
%
%ADD23MACRO23*%
%ADD55C,.01*%
%ADD56C,.011*%
%ADD57C,.014*%
%ADD58C,.015*%
%ADD59C,.018*%
%ADD60C,.004*%
%ADD61C,.006*%
%ADD62C,.007*%
G75*
%LPD*%
G75*
G36*
G01X15748Y1324772D02*
X187795D01*
G02X201543Y1311024I0J-13748D01*
G01Y879298D01*
G02X201542Y879279I-200J1D01*
G01Y850964D01*
X201543Y850963D01*
Y392315D01*
G02X201542Y392295I-200J0D01*
G01Y383705D01*
G02X201543Y383685I-199J-20D01*
G01Y15748D01*
G02X189551Y2113I-13748J0D01*
G02X189525Y2111I-28J198D01*
G01X145503D01*
G02X145361Y2170I0J200D01*
G01X140799Y6732D01*
G02X140740Y6874I141J142D01*
G01Y43307D01*
G03X134195Y50029I-6724J0D01*
G02X134000Y50229I5J200D01*
G01Y51622D01*
G02X134062Y51767I200J0D01*
G01X134271Y51967D01*
G02X134418Y52022I138J-145D01*
G02X142739Y43307I-403J-8715D01*
G01Y7645D01*
G03X142798Y7503I200J0D01*
G01X146243Y4058D01*
G03X146385Y3999I142J141D01*
G01X187795D01*
G03X199544Y15748I0J11749D01*
G01Y1311024D01*
G03X187795Y1322773I-11749J0D01*
G01X15748D01*
G03X3999Y1311024I0J-11749D01*
G01Y696916D01*
G03X3998Y696855I1550J-56D01*
G01Y665991D01*
G03X3999Y665930I1551J-5D01*
G01Y15748D01*
G03X15748Y3999I11749J0D01*
G01X57158D01*
G03X57300Y4058I0J200D01*
G01X60745Y7503D01*
G03X60804Y7645I-141J142D01*
G01Y43307D01*
G02X69080Y52019I8723J0D01*
G02X69228Y51964I10J-200D01*
G01X69438Y51764D01*
G02X69500Y51619I-138J-145D01*
G01Y50227D01*
G02X69307Y50027I-200J0D01*
G03X62803Y43307I220J-6720D01*
G01Y6851D01*
G02X62744Y6709I-200J0D01*
G01X58105Y2070D01*
G02X57963Y2011I-142J141D01*
G01X15194D01*
G02X2000Y15748I554J13737D01*
G01Y41959D01*
G02X2001Y41978I200J-1D01*
G01Y374422D01*
G02X2000Y374441I199J20D01*
G01Y489175D01*
G02X2001Y489196I200J1D01*
G01Y492154D01*
G02X2000Y492175I199J20D01*
G01Y846358D01*
G02X2001Y846378I200J0D01*
G01Y865379D01*
X2000Y865380D01*
Y1311024D01*
G02X15748Y1324772I13748J0D01*
G37*
G36*
G01X11570Y211720D02*
X15100D01*
X16080Y210740D01*
Y207921D01*
X24726Y199275D01*
Y173909D01*
X31900Y166735D01*
Y142994D01*
G02X31841Y142852I-200J0D01*
G01X31480Y142491D01*
G02X31338Y142432I-142J141D01*
G01X21112D01*
X20290Y141610D01*
X7870D01*
X7810Y141670D01*
Y143850D01*
X10902Y146942D01*
Y211052D01*
X11570Y211720D01*
G37*
G36*
G01X8360Y863830D02*
X56170D01*
X58441Y861559D01*
G02X58500Y861417I-141J-142D01*
G01Y858694D01*
G02X58493Y858639I-200J-2D01*
G01X58471Y858563D01*
X58458Y858541D01*
G03X57898Y856500I3442J-2042D01*
G01Y852500D01*
G03X58370Y850616I4002J1D01*
G01X58381Y850595D01*
X58393Y850549D01*
G02Y850451I-194J-49D01*
G01X58381Y850405D01*
X58370Y850384D01*
G03X57898Y848500I3530J-1885D01*
G01Y847700D01*
G02X57698Y847500I-200J0D01*
G01X8200D01*
G02X8000Y847700I0J200D01*
G01Y850419D01*
X8001Y850424D01*
G03X8007Y850673I-4996J245D01*
G01Y850675D01*
G03X8001Y850925I-5001J5D01*
G01X8000Y850930D01*
Y863470D01*
X8360Y863830D01*
G37*
G36*
G01X9270Y938290D02*
X12840D01*
X15950Y935180D01*
Y906093D01*
X15980Y906020D01*
X15998Y906002D01*
Y905993D01*
X36241Y885750D01*
G02X36300Y885608I-141J-142D01*
G01Y868202D01*
G02X36100Y868002I-200J0D01*
G01X28669D01*
X28634Y868017D01*
G03X28557Y868032I-76J-185D01*
G01X24822D01*
X21790Y865000D01*
X9620D01*
X8000Y866620D01*
Y937020D01*
X9270Y938290D01*
G37*
G36*
G01X7380Y1223520D02*
X13836D01*
X14032Y1223324D01*
Y1217057D01*
X14820Y1216269D01*
Y1213530D01*
X14740Y1213450D01*
X7470D01*
X7020Y1213900D01*
Y1223160D01*
X7380Y1223520D01*
G37*
G36*
G01X14602Y233100D02*
X20117D01*
G02X20259Y233041I0J-200D01*
G01X29291Y224009D01*
G03X29433Y223950I142J141D01*
G01X69967D01*
G02X70109Y223891I0J-200D01*
G01X73165Y220835D01*
X73182Y220700D01*
X73148Y220641D01*
G03X71998Y216400I7252J-4243D01*
G01Y148200D01*
G02X71956Y148078I-200J1D01*
G03X71322Y147106I5948J-4572D01*
G02X71147Y147002I-175J96D01*
G01X69100D01*
G03X65288Y145960I2J-7501D01*
G02X65186Y145932I-102J172D01*
G01X39602D01*
G02X39402Y146132I0J200D01*
G01Y170324D01*
Y173408D01*
X36174Y176636D01*
X33450Y179360D01*
Y201160D01*
X17360Y217250D01*
X14402Y220208D01*
X13460Y221150D01*
Y227630D01*
Y232230D01*
X14320Y233090D01*
X14540D01*
G02X14602Y233100I62J-190D01*
G37*
G36*
G01X69424Y248898D02*
X71194D01*
G02X71336Y248839I0J-200D01*
G01X71741Y248434D01*
G02X71800Y248292I-141J-142D01*
G01Y228783D01*
G02X71741Y228641I-200J0D01*
G01X70859Y227759D01*
G02X70717Y227700I-142J141D01*
G01X30083D01*
G02X29941Y227759I0J200D01*
G01X25759Y231941D01*
G02X25700Y232083I141J142D01*
G01Y236308D01*
G02X25759Y236450I200J0D01*
G01X25838Y236529D01*
X25911Y236559D01*
X25988D01*
G03X26090Y236560I-32J8502D01*
G01X27121Y237591D01*
X34488D01*
X34490D01*
X46908D01*
G03X47050Y237650I0J200D01*
G01X47535Y238135D01*
X47542Y238141D01*
G03X48754Y239353I-5375J6587D01*
G01X48760Y239360D01*
X48800Y239400D01*
Y239409D01*
X48843Y239463D01*
G03X50669Y244728I-6676J5265D01*
G03X50388Y246897I-8502J1D01*
G01X50376Y246942D01*
X50394Y247032D01*
X50616Y247321D01*
G02X50775Y247398I158J-123D01*
G01X67758D01*
G03X67900Y247457I0J200D01*
G01X69282Y248839D01*
G02X69424Y248898I142J-141D01*
G37*
G36*
G01X14350Y301453D02*
X31491D01*
X32200Y300744D01*
Y285983D01*
G02X32141Y285841I-200J0D01*
G01X31087Y284787D01*
G02X30945Y284728I-142J141D01*
G01X14768D01*
G02X14626Y284787I0J200D01*
G01X13744Y285669D01*
G02X13685Y285811I141J142D01*
G01Y300788D01*
X14350Y301453D01*
G37*
G36*
G01X29892Y324400D02*
X43117D01*
G02X43259Y324341I0J-200D01*
G01X53641Y313959D01*
X53642Y313958D01*
X53700Y313900D01*
Y310644D01*
X53642Y310586D01*
X53641Y310585D01*
X53131Y310075D01*
X53130Y310074D01*
X53072Y310016D01*
X16149D01*
X15359Y310806D01*
X15358Y310807D01*
X15300Y310865D01*
Y323447D01*
G02X15359Y323589I200J0D01*
G01X16000Y324230D01*
G02X16142Y324288I141J-142D01*
G01X29654D01*
G03X29796Y324347I0J200D01*
G01X29819Y324370D01*
X29892Y324400D01*
G37*
G36*
G01X12690Y337420D02*
X26900D01*
X27770Y336550D01*
Y332930D01*
X26630Y331790D01*
X12900D01*
X11780Y332910D01*
Y336510D01*
X12690Y337420D01*
G37*
G36*
G01X58998Y370500D02*
Y340176D01*
G03X59057Y340034I200J0D01*
G01X68041Y331050D01*
G02X68100Y330908I-141J-142D01*
G01Y314183D01*
G02X68041Y314041I-200J0D01*
G01X67459Y313459D01*
G02X67317Y313400I-142J141D01*
G01X58983D01*
G02X58841Y313459I0J200D01*
G01X58659Y313641D01*
G02X58600Y313783I141J142D01*
G01Y315917D01*
G03X58541Y316059I-200J0D01*
G01X35330Y339270D01*
G02X35272Y339411I142J141D01*
G01Y339574D01*
G03X35213Y339716I-200J0D01*
G01X30066Y344863D01*
G03X29924Y344922I-142J-141D01*
G01X17061D01*
G02X16920Y344980I0J200D01*
G01X15659Y346241D01*
G02X15600Y346383I141J142D01*
G01Y363500D01*
X17600Y365500D01*
X34500D01*
X36500D01*
X39500D01*
X40000D01*
X46000Y371500D01*
X51000D01*
X57998D01*
X58998Y370500D01*
G37*
G36*
G01X15920Y500000D02*
X22417D01*
G02X22559Y499941I0J-200D01*
G01X22941Y499559D01*
G02X23000Y499417I-141J-142D01*
G01Y490083D01*
G02X22941Y489941I-200J0D01*
G01X22559Y489559D01*
G02X22417Y489500I-142J141D01*
G01X14670D01*
X14180Y489990D01*
Y498260D01*
X15920Y500000D01*
G37*
G36*
G01X13983Y960700D02*
X19917D01*
G02X20059Y960641I0J-200D01*
G01X20841Y959859D01*
G02X20900Y959717I-141J-142D01*
G01Y957083D01*
G03X20959Y956941I200J0D01*
G01X28041Y949859D01*
G03X28183Y949800I142J141D01*
G01X70417D01*
G02X70559Y949741I0J-200D01*
G01X72941Y947359D01*
G02X73000Y947217I-141J-142D01*
G01Y871583D01*
G02X72941Y871441I-200J0D01*
G01X71559Y870059D01*
G02X71417Y870000I-142J141D01*
G01X60692D01*
G02X60550Y870059I0J200D01*
G01X59166Y871443D01*
G03X59024Y871502I-142J-141D01*
G01X47500D01*
G02X47300Y871702I0J200D01*
G01Y885217D01*
G03X47241Y885359I-200J0D01*
G01X23559Y909041D01*
G02X23500Y909183I141J142D01*
G01Y934317D01*
X12800Y945017D01*
Y959517D01*
G02X12859Y959659I200J0D01*
G01X13841Y960641D01*
G02X13983Y960700I142J-141D01*
G37*
G36*
G01X48432Y976082D02*
X69435D01*
X70100Y975417D01*
Y954883D01*
G02X70041Y954741I-200J0D01*
G01X69359Y954059D01*
G02X69217Y954000I-142J141D01*
G01X30683D01*
G02X30541Y954059I0J200D01*
G01X25627Y958973D01*
G02X25568Y959115I141J142D01*
G01Y960512D01*
G02X25730Y960701I200J-7D01*
G01Y962260D01*
X26410Y962940D01*
X41680D01*
X47710Y968970D01*
Y975360D01*
X48432Y976082D01*
G37*
G36*
G01X25982Y1029800D02*
X25984D01*
G02X26210Y1029775I4J-1000D01*
G01X26259Y1029763D01*
X26262D01*
X27101Y1029580D01*
G03X27144Y1029576I40J196D01*
G01X32514D01*
G02X32714Y1029376I0J-200D01*
G01Y1006934D01*
G02X32655Y1006792I-200J0D01*
G01X31307Y1005444D01*
G02X31165Y1005385I-142J141D01*
G01X12498D01*
G02X12356Y1005444I0J200D01*
G01X11559Y1006241D01*
G02X11500Y1006383I141J142D01*
G01Y1029231D01*
G02X11567Y1029381I200J1D01*
G01X11823Y1029608D01*
X11903Y1029633D01*
X11947Y1029628D01*
G03X12846Y1029576I893J7649D01*
G01X15826D01*
G03X15869Y1029580I3J200D01*
G01X16708Y1029763D01*
X16711D01*
X16760Y1029775D01*
G02X16986Y1029800I222J-975D01*
G01X16988D01*
G02X17160Y1029785I-1J-1000D01*
G03X19810I1325J7587D01*
G02X19983Y1029800I173J-985D01*
G01X19987D01*
G02X20160Y1029785I0J-1000D01*
G03X22810I1325J7587D01*
G02X22983Y1029800I173J-985D01*
G01X22987D01*
G02X23160Y1029785I0J-1000D01*
G03X25810I1325J7587D01*
G02X25982Y1029800I173J-985D01*
G37*
G36*
G01X13020Y1052830D02*
X32279D01*
X32547Y1052562D01*
X32548Y1052561D01*
X41744Y1043365D01*
G03X41885Y1043307I141J142D01*
G01X51900D01*
X54132Y1041075D01*
Y1037525D01*
X53684Y1037077D01*
X27928D01*
X27905Y1037082D01*
G03X25985Y1037302I-1922J-8282D01*
G01X25981D01*
G03X24519Y1037175I2J-8502D01*
G02X24451I-34J197D01*
G03X22987Y1037302I-1464J-8375D01*
G01X22983D01*
G03X21519Y1037175I0J-8502D01*
G02X21451I-34J197D01*
G03X19987Y1037302I-1464J-8375D01*
G01X19983D01*
G03X18519Y1037175I0J-8502D01*
G02X18451I-34J197D01*
G03X16989Y1037302I-1464J-8375D01*
G01X16985D01*
G03X15065Y1037082I2J-8502D01*
G01X15042Y1037077D01*
X12847D01*
G02X12705Y1037136I0J200D01*
G01X12159Y1037682D01*
G02X12100Y1037824I141J142D01*
G01Y1050408D01*
Y1050409D01*
Y1051910D01*
X13020Y1052830D01*
G37*
G36*
G01X12828Y1066498D02*
X26492D01*
X26840Y1066150D01*
X26860D01*
G02X27060Y1065950I0J-200D01*
G01Y1061689D01*
X26266Y1060895D01*
X12784D01*
X11925Y1061754D01*
Y1065595D01*
X12828Y1066498D01*
G37*
G36*
G01X17483Y1108500D02*
X58220D01*
G02X58351Y1108451I0J-200D01*
G03X63712Y1106281I5879J6817D01*
G02X63900Y1106082I-12J-200D01*
G01Y1062683D01*
Y1061474D01*
X64898Y1060476D01*
G03X64957Y1060334I200J0D01*
G01X68724Y1056567D01*
X68736Y1056549D01*
G03X71304Y1053981I7157J4589D01*
G01X71322Y1053969D01*
X71441Y1053850D01*
G02X71500Y1053708I-141J-142D01*
G01Y1040583D01*
G02X71441Y1040441I-200J0D01*
G01X71059Y1040059D01*
G02X70917Y1040000I-142J141D01*
G01X61834D01*
X59930D01*
X59710Y1040220D01*
X59130Y1040800D01*
Y1046360D01*
X54682Y1050808D01*
X45155D01*
G02X45013Y1050867I0J200D01*
G01X34621Y1061259D01*
G02X34562Y1061401I141J142D01*
G01Y1068954D01*
Y1069755D01*
Y1069838D01*
X33592Y1070808D01*
X33591Y1070809D01*
X30459Y1073941D01*
G03X30317Y1074000I-142J-141D01*
G01X18183D01*
G02X18041Y1074059I0J200D01*
G01X15759Y1076341D01*
G02X15700Y1076483I141J142D01*
G01Y1106717D01*
G02X15759Y1106859I200J0D01*
G01X17341Y1108441D01*
G02X17483Y1108500I142J-141D01*
G37*
G36*
G01X17038Y1223470D02*
X33100D01*
X33670Y1222900D01*
Y1214690D01*
X32650Y1213670D01*
X16250D01*
X16170Y1213750D01*
Y1216233D01*
X16952Y1217015D01*
Y1223384D01*
X17038Y1223470D01*
G37*
G36*
G01X48883Y274000D02*
X64084D01*
G02X64226Y273941I0J-200D01*
G01X65667Y272500D01*
X65775Y272393D01*
G02X65834Y272251I-141J-142D01*
G01Y256083D01*
G02X65775Y255941I-200J0D01*
G01X64793Y254959D01*
G02X64651Y254900I-142J141D01*
G01X49383D01*
G02X49241Y254959I0J200D01*
G01X48459Y255741D01*
G02X48400Y255883I141J142D01*
G01Y273517D01*
G02X48459Y273659I200J0D01*
G01X48741Y273941D01*
G02X48883Y274000I142J-141D01*
G37*
G36*
G01X47683Y997900D02*
X66367D01*
X66384Y997884D01*
X71533D01*
G02X71675Y997825I0J-200D01*
G01X72141Y997359D01*
G02X72200Y997217I-141J-142D01*
G01Y984802D01*
G02X72000Y984602I-200J0D01*
G01X47400D01*
G02X47200Y984802I0J200D01*
G01Y997417D01*
G02X47259Y997559I200J0D01*
G01X47541Y997841D01*
G02X47683Y997900I142J-141D01*
G37*
G36*
G01X77983Y48500D02*
X87917D01*
G02X88059Y48441I0J-200D01*
G01X89441Y47059D01*
G02X89500Y46917I-141J-142D01*
G01Y7478D01*
G02X89324Y7280I-199J0D01*
G01X86570D01*
G02X86396Y7454I25J199D01*
G01Y27180D01*
X84590D01*
Y7464D01*
G02X84414Y7280I-199J15D01*
G01X81676D01*
G02X81500Y7478I23J198D01*
G01Y25417D01*
G03X81441Y25559I-200J0D01*
G01X81425Y25575D01*
X81396Y25644D01*
Y27180D01*
X79880D01*
G02X79763Y27237I24J199D01*
G01X77459Y29541D01*
G02X77400Y29683I141J142D01*
G01Y47917D01*
G02X77459Y48059I200J0D01*
G01X77841Y48441D01*
G02X77983Y48500I142J-141D01*
G37*
G36*
G01X66500Y343200D02*
Y374728D01*
X67644Y375872D01*
X68543D01*
X88543D01*
X90043Y374372D01*
Y342372D01*
X90036Y342364D01*
Y336836D01*
X88900Y335700D01*
X74000D01*
X66500Y343200D01*
G37*
G36*
G01X72400Y1063500D02*
Y1095900D01*
X73544Y1097044D01*
X74443D01*
X94443D01*
X95943Y1095544D01*
Y1063544D01*
Y1059543D01*
Y1055943D01*
X93900Y1053900D01*
X82000D01*
X72400Y1063500D01*
G37*
G36*
G01X120640Y50850D02*
X124350D01*
X124950D01*
X126650D01*
X127000Y50500D01*
Y34000D01*
X125422Y32422D01*
Y32122D01*
Y7622D01*
X125088Y7288D01*
X124800D01*
X111695D01*
G02X111553Y7347I0J200D01*
G01X110559Y8341D01*
G02X110500Y8483I141J142D01*
G01Y26048D01*
Y31153D01*
X111147Y31800D01*
X116000D01*
X120000Y35800D01*
Y50210D01*
X120640Y50850D01*
G37*
G36*
G01X119120Y301410D02*
X141702D01*
X142500Y300612D01*
Y285783D01*
G02X142441Y285641I-200J0D01*
G01X141587Y284787D01*
G02X141445Y284728I-142J141D01*
G01X119655D01*
G02X119513Y284787I0J200D01*
G01X118159Y286141D01*
G02X118100Y286283I141J142D01*
G01Y300390D01*
X119120Y301410D01*
G37*
G36*
G01X119623Y328880D02*
X142737D01*
G02X142879Y328821I0J-200D01*
G01X155106Y316594D01*
G03X155248Y316535I142J141D01*
G01X160917D01*
G02X161059Y316476I0J-200D01*
G01X162941Y314594D01*
G02X163000Y314452I-141J-142D01*
G01Y310407D01*
G02X162941Y310265I-200J0D01*
G01X162669Y309993D01*
X162599Y309963D01*
X162560Y309962D01*
G03X162354Y309954I227J-8499D01*
G01X162296Y309896D01*
X119304D01*
X118800Y310400D01*
Y328057D01*
G02X118859Y328199I200J0D01*
G01X119481Y328821D01*
G02X119623Y328880I142J-141D01*
G37*
G36*
G01X132200Y373600D02*
X132900Y372900D01*
Y337500D01*
X131800Y336400D01*
X111900D01*
X111000Y337300D01*
Y342228D01*
Y372100D01*
X112500Y373600D01*
X132200D01*
G37*
G36*
G01X124002Y1028238D02*
X137006D01*
X137982Y1027262D01*
Y1012583D01*
G02X137923Y1012441I-200J0D01*
G01X137041Y1011559D01*
X137013Y1011530D01*
X136939Y1011500D01*
X124065D01*
G02X123923Y1011559I0J200D01*
G01X123041Y1012441D01*
X123012Y1012469D01*
X122982Y1012543D01*
Y1027218D01*
X124002Y1028238D01*
G37*
G36*
G01X118500Y1056619D02*
X135989D01*
G02X136131Y1056560I0J-200D01*
G01X146282Y1046409D01*
G03X149379Y1044519I5447J5444D01*
G01X149381Y1044518D01*
X149404Y1044510D01*
X149423Y1044499D01*
G02X149461Y1044469I-104J-171D01*
G01X149817Y1044113D01*
G03X155259Y1041860I5443J5449D01*
G01X162175D01*
G02X162317Y1041801I0J-200D01*
G01X162841Y1041277D01*
G02X162900Y1041135I-141J-142D01*
G01Y1037129D01*
G02X162841Y1036987I-200J0D01*
G01X162415Y1036561D01*
G02X162273Y1036502I-142J141D01*
G01X157181D01*
G02X157094Y1036522I0J200D01*
G03X156478Y1036794I-3942J-8093D01*
G01X156439Y1036810D01*
X155778Y1037471D01*
G03X155636Y1037530I-142J-141D01*
G01X119326D01*
G02X119184Y1037589I0J200D01*
G01X118359Y1038414D01*
G02X118300Y1038556I141J142D01*
G01Y1056419D01*
G02X118500Y1056619I200J0D01*
G37*
G36*
G01X112500Y1102500D02*
X131480D01*
X132820Y1101160D01*
Y1065140D01*
X131980Y1064300D01*
X112300D01*
X111000Y1065600D01*
Y1069000D01*
Y1101000D01*
X112500Y1102500D01*
G37*
G36*
G01X130683Y233200D02*
X143617D01*
G02X143759Y233141I0J-200D01*
G01X156941Y219959D01*
G03X157083Y219900I142J141D01*
G01X169160D01*
X169176Y219884D01*
G02X169282Y219778I-78J-184D01*
G01X169800Y219260D01*
Y174540D01*
X162898Y167638D01*
Y145479D01*
G02X162840Y145338I-200J0D01*
G01X162467Y144965D01*
G02X162325Y144906I-142J141D01*
G01X134343D01*
G02X134161Y145024I0J200D01*
G03X132532Y147423I-7661J-3449D01*
G02X132487Y147629I144J139D01*
G03X133002Y150630I-8486J3001D01*
G01Y150633D01*
G03X132415Y153829I-9002J-2D01*
G02X132402Y153900I187J71D01*
G01Y216000D01*
G03X129941Y221941I-8401J0D01*
G01X128959Y222923D01*
G02X128900Y223064I141J142D01*
G01Y232240D01*
X129740Y233080D01*
X130480D01*
X130541Y233141D01*
G02X130683Y233200I142J-141D01*
G37*
G36*
G01X176094Y373600D02*
X187703D01*
G02X187845Y373541I0J-200D01*
G01X189327Y372059D01*
G02X189386Y371917I-141J-142D01*
G01Y358912D01*
X189214Y358740D01*
X173481D01*
X168617Y353876D01*
G03X168558Y353734I141J-142D01*
G01Y330952D01*
Y329940D01*
X176400Y322098D01*
Y313783D01*
G02X176341Y313641I-200J0D01*
G01X175459Y312759D01*
G02X175317Y312700I-142J141D01*
G01X167983D01*
G02X167841Y312759I0J200D01*
G01X167359Y313241D01*
G02X167300Y313383I141J142D01*
G01Y315717D01*
G03X167241Y315859I-200J0D01*
G01X163159Y319941D01*
G03X163017Y320000I-142J-141D01*
G01X158583D01*
G02X158441Y320059I0J200D01*
G01X140559Y337941D01*
G02X140500Y338083I141J142D01*
G01Y371417D01*
G02X140559Y371559I200J0D01*
G01X142040Y373040D01*
G02X142181Y373098I141J-142D01*
G01X173200D01*
G03X176027Y373588I0J8402D01*
G02X176094Y373600I68J-188D01*
G37*
G36*
G01X134102Y963200D02*
X143517D01*
G02X143659Y963141I0J-200D01*
G01X159041Y947759D01*
G03X159183Y947700I142J141D01*
G01X169217D01*
G02X169359Y947641I0J-200D01*
G01X170941Y946059D01*
G02X171000Y945917I-141J-142D01*
G01Y917083D01*
G02X170941Y916941I-200J0D01*
G01X157309Y903309D01*
G03X157250Y903167I141J-142D01*
G01Y871833D01*
G02X157191Y871691I-200J0D01*
G01X155559Y870059D01*
G02X155417Y870000I-142J141D01*
G01X134102D01*
G02X133902Y870200I0J200D01*
G01Y963000D01*
G02X134102Y963200I200J0D01*
G37*
G36*
G01X142083Y1110500D02*
X189917D01*
G02X190059Y1110441I0J-200D01*
G01X191441Y1109059D01*
G02X191500Y1108917I-141J-142D01*
G01Y1074683D01*
G02X191441Y1074541I-200J0D01*
G01X190359Y1073459D01*
G02X190217Y1073400I-142J141D01*
G01X174083D01*
X172408D01*
X171307Y1072299D01*
Y1056732D01*
X178800Y1049239D01*
Y1039383D01*
G02X178741Y1039241I-200J0D01*
G01X177859Y1038359D01*
G02X177717Y1038300I-142J141D01*
G01X170370D01*
X167850Y1040820D01*
Y1043821D01*
X162309Y1049362D01*
X155260D01*
G02X155118Y1049421I0J200D01*
G01X152946Y1051593D01*
X152945Y1051594D01*
X140728Y1063811D01*
X140500D01*
Y1108917D01*
G02X140559Y1109059I200J0D01*
G01X141941Y1110441D01*
G02X142083Y1110500I142J-141D01*
G37*
G36*
G01X174560Y244963D02*
X188630D01*
G02X188772Y244904I0J-200D01*
G01X189341Y244335D01*
G02X189400Y244193I-141J-142D01*
G01Y227430D01*
X188340Y226370D01*
X155230D01*
X148759Y232841D01*
G02X148700Y232983I141J142D01*
G01Y234887D01*
G02X148759Y235029I200J0D01*
G01X149490Y235760D01*
Y235800D01*
X149930Y236240D01*
X162124D01*
G03X162130Y236242I-2844J8541D01*
G02X162205Y236251I61J-190D01*
G03X162369Y236240I651J8477D01*
G01X163348D01*
G03X164324Y236353I-488J8488D01*
G02X164392I34J-197D01*
G03X165368Y236240I1464J8375D01*
G01X166345D01*
G03X170428Y237559I-487J8488D01*
G02X170430Y237561I139J-137D01*
G01X170431D01*
G02X170536Y237591I105J-170D01*
G01X170708D01*
G03X170850Y237650I0J200D01*
G01X172270Y239070D01*
X172300Y239143D01*
Y239179D01*
X172347Y239235D01*
G03X174360Y244728I-6488J5493D01*
G01Y244763D01*
G02X174560Y244963I200J0D01*
G37*
G36*
G01X179961Y944378D02*
X198122D01*
X198600Y943900D01*
Y871790D01*
X198490Y871680D01*
X196520D01*
X196000Y872200D01*
X167700D01*
X166500Y873400D01*
Y899917D01*
G02X166559Y900059I200J0D01*
G01X179441Y912941D01*
G03X179500Y913083I-141J142D01*
G01Y943917D01*
G02X179559Y944059I200J0D01*
G01X179819Y944319D01*
G02X179961Y944378I142J-141D01*
G37*
G36*
G01X175173Y971998D02*
X187819D01*
G02X187961Y971939I0J-200D01*
G01X188841Y971059D01*
G02X188900Y970917I-141J-142D01*
G01Y952940D01*
X187840Y951880D01*
X160303D01*
G02X160161Y951939I0J200D01*
G01X151460Y960640D01*
X151390D01*
X149940Y962090D01*
Y962160D01*
X149859Y962241D01*
G02X149800Y962383I141J142D01*
G01Y962652D01*
G02X149860Y962795I200J0D01*
G01X149940Y962873D01*
Y965530D01*
X150550Y966140D01*
X164642D01*
G03X165956Y967611I-5641J6361D01*
G02X166119Y967696I164J-115D01*
G01X170704D01*
G03X170846Y967755I0J200D01*
G01X172611Y969519D01*
X172626Y969529D01*
G03X174729Y971632I-4868J6971D01*
G01X174739Y971647D01*
X175031Y971939D01*
G02X175173Y971998I142J-141D01*
G37*
G36*
G01X178154Y218479D02*
X195113D01*
X195911Y217681D01*
Y143781D01*
X195730Y143600D01*
X171875D01*
X170459Y145016D01*
G02X170400Y145158I141J142D01*
G01Y164448D01*
G02X170459Y164590I200J0D01*
G01X177243Y171374D01*
G03X177302Y171516I-141J142D01*
G01Y215353D01*
G02X177307Y215400I200J3D01*
G03X177566Y217543I-8743J2144D01*
G03X177559Y217884I-9002J-14D01*
G01X178154Y218479D01*
G37*
G36*
G01X171683Y270900D02*
X190317D01*
G02X190459Y270841I0J-200D01*
G01X191341Y269959D01*
G02X191400Y269817I-141J-142D01*
G01Y253183D01*
G02X191341Y253041I-200J0D01*
G01X190823Y252523D01*
G02X190682Y252464I-142J141D01*
G01X171718D01*
G02X171577Y252523I1J200D01*
G01X171059Y253041D01*
G02X171000Y253183I141J142D01*
G01Y270217D01*
G02X171059Y270359I200J0D01*
G01X171541Y270841D01*
G02X171683Y270900I142J-141D01*
G37*
G36*
G01X177036Y350234D02*
X191713D01*
X192600Y349347D01*
Y333883D01*
G02X192541Y333741I-200J0D01*
G01X190259Y331459D01*
G02X190117Y331400I-142J141D01*
G01X178175D01*
X176060Y333515D01*
Y349258D01*
X177036Y350234D01*
G37*
G36*
G01X189910Y499000D02*
X196917D01*
G02X197059Y498941I0J-200D01*
G01X197441Y498559D01*
G02X197500Y498417I-141J-142D01*
G01Y489083D01*
G02X197441Y488941I-200J0D01*
G01X197059Y488559D01*
G02X196917Y488500I-142J141D01*
G01X189610D01*
X189140Y488970D01*
Y498230D01*
X189910Y499000D01*
G37*
G36*
G01X196520Y870320D02*
X198460D01*
X198500Y870280D01*
Y868400D01*
X197100Y867000D01*
Y853759D01*
X196841Y853500D01*
X192302D01*
G02X192102Y853700I0J200D01*
G01Y862898D01*
X189500Y865500D01*
Y869600D01*
X189700Y869800D01*
X196000D01*
X196520Y870320D01*
G37*
G36*
G01X194000Y997817D02*
Y981583D01*
G02X193941Y981441I-200J0D01*
G01X192059Y979559D01*
G02X191917Y979500I-142J141D01*
G01X175783D01*
G02X175641Y979559I0J200D01*
G01X174759Y980441D01*
G02X174700Y980583I141J142D01*
G01Y992117D01*
G02X174759Y992259I200J0D01*
G01X181641Y999141D01*
G02X181783Y999200I142J-141D01*
G01X192617D01*
G02X192759Y999141I0J-200D01*
G01X193941Y997959D01*
G02X194000Y997817I-141J-142D01*
G37*
G36*
G01X192759Y1066331D02*
G02X192967Y1066283I66J-189D01*
G01X193391Y1065859D01*
G02X193450Y1065717I-141J-142D01*
G01Y1058033D01*
G02X193391Y1057891I-200J0D01*
G01X192259Y1056759D01*
G02X192117Y1056700I-142J141D01*
G01X183027D01*
X180355Y1059372D01*
Y1065233D01*
X181020Y1065898D01*
X190218D01*
G03X192759Y1066331I-5J7701D01*
G37*
G36*
G01X188930Y1223820D02*
X196470D01*
X196890Y1223400D01*
Y1213970D01*
X196650Y1213730D01*
X188820D01*
X188670Y1213880D01*
Y1223560D01*
X188930Y1223820D01*
G37*
G36*
G01X187094Y1223606D02*
X187340Y1223360D01*
Y1214100D01*
X186940Y1213700D01*
X170810D01*
X170530Y1213980D01*
Y1223420D01*
X170716Y1223606D01*
X187094D01*
G37*
G54D10*
X-58189Y19685D03*
Y619685D03*
Y1307087D03*
X20000Y1307000D03*
X44000Y17500D03*
X178500D03*
X865353Y19685D03*
Y1307087D03*
G54D20*
X26378Y48858D03*
Y412244D03*
Y775630D03*
Y1139016D03*
X177165Y103976D03*
Y467362D03*
Y830748D03*
Y1194134D03*
G54D11*
X-58431Y824000D03*
X-63431Y837184D03*
Y1152816D03*
X-58431Y1166000D03*
X-53431Y837184D03*
Y1152816D03*
X-27318Y824000D03*
X-32318Y837184D03*
X-22318D03*
X-32318Y1152816D03*
X-22318D03*
X-27318Y1166000D03*
G54D30*
X33500Y516500D03*
X173000Y518000D03*
G54D21*
X14700Y144531D03*
Y137531D03*
X23400Y383500D03*
X14600Y379500D03*
Y387500D03*
X18600Y867000D03*
Y860000D03*
X55600Y850500D03*
X71600Y137500D03*
X64400Y846500D03*
Y854500D03*
X80400Y133500D03*
Y141500D03*
X122100Y131000D03*
Y139000D03*
X130900Y135000D03*
X189054Y145631D03*
Y138631D03*
X194900Y388000D03*
X186100Y384000D03*
Y392000D03*
X192000Y867500D03*
X194400Y856000D03*
X185600Y852000D03*
Y860000D03*
X192000Y874500D03*
G54D12*
X3005Y30675D03*
X7500Y44000D03*
X3005Y50675D03*
Y70675D03*
Y90675D03*
Y110675D03*
Y130675D03*
Y150675D03*
Y170675D03*
X8908Y163243D03*
Y160243D03*
X3005Y190675D03*
Y210675D03*
Y230675D03*
Y250675D03*
Y270675D03*
Y290675D03*
Y310675D03*
Y330675D03*
Y350675D03*
Y370675D03*
Y390675D03*
Y410675D03*
Y430675D03*
Y450675D03*
Y470675D03*
Y490675D03*
Y510675D03*
Y530675D03*
Y550675D03*
Y570675D03*
Y590675D03*
Y610675D03*
X12000Y641000D03*
X3005Y630675D03*
Y650675D03*
Y670675D03*
Y690675D03*
Y710675D03*
Y730675D03*
X6025Y734000D03*
X6000Y727000D03*
X3005Y750675D03*
X6025Y748000D03*
Y741000D03*
X3005Y770675D03*
Y790675D03*
Y810675D03*
Y830675D03*
Y850675D03*
Y870675D03*
Y890675D03*
Y910675D03*
Y930675D03*
Y950675D03*
Y970675D03*
X9838Y994729D03*
X3005Y990675D03*
Y1010675D03*
Y1030675D03*
Y1050675D03*
Y1070675D03*
Y1090675D03*
Y1110675D03*
Y1130675D03*
Y1150675D03*
Y1170675D03*
Y1190675D03*
Y1210675D03*
Y1230675D03*
X8000Y1220000D03*
Y1222500D03*
X3005Y1250675D03*
Y1270675D03*
Y1290675D03*
Y1310675D03*
X15868Y3010D03*
X11874Y154893D03*
X13708Y173943D03*
Y170943D03*
X11208Y173943D03*
Y170943D03*
X13080Y179343D03*
Y182343D03*
Y192843D03*
Y189843D03*
X13580Y201643D03*
Y198643D03*
X14791Y210028D03*
Y207028D03*
X29191Y207428D03*
X17782Y248150D03*
X26040Y245190D03*
X29291Y235093D03*
X26791D03*
X31871D03*
X26791Y232593D03*
X29331D03*
X31871D03*
X25545Y248578D03*
X14587Y231944D03*
X17087D03*
X19667D03*
Y229444D03*
X17127D03*
X14587D03*
X12791Y261000D03*
X17953Y267500D03*
X27912Y270676D03*
X32000Y261000D03*
X10000Y267303D03*
X27185Y286228D03*
X21185D03*
X24185D03*
X27185Y289228D03*
X21185D03*
X24185D03*
X18185Y286228D03*
Y289228D03*
X21185Y312228D03*
Y315228D03*
X18185D03*
X24185Y312228D03*
X27185Y315228D03*
X24185D03*
X14000Y335928D03*
X17000D03*
X20000D03*
X23000D03*
X26000D03*
X26500Y358728D03*
X23500D03*
X20500D03*
X17500D03*
X20500Y361728D03*
X23500D03*
X11000Y502000D03*
X18000Y491500D03*
X20500Y497500D03*
Y495000D03*
X11000Y511000D03*
X10987Y523418D03*
X29500Y520500D03*
Y512500D03*
X11000Y520000D03*
Y515500D03*
Y506500D03*
X20452Y513547D03*
X27580Y528341D03*
X29500Y534075D03*
X28900Y556900D03*
X30380Y648320D03*
X32720Y660000D03*
X32258Y646000D03*
X21000Y644000D03*
X32760Y657000D03*
X21525Y660000D03*
Y654000D03*
X12389Y653509D03*
X12512Y647013D03*
X25023Y663850D03*
X14925Y663000D03*
X21525Y666500D03*
X32760Y669500D03*
X21525Y672500D03*
X32760Y682000D03*
X25023Y669850D03*
X32728Y679000D03*
X12500D03*
X14925Y669000D03*
Y690000D03*
X13000Y709000D03*
X20453Y708047D03*
X15713Y710009D03*
X20327Y711174D03*
X17500Y734000D03*
X26500Y732500D03*
X13425Y712500D03*
X13375Y730274D03*
X17500Y741000D03*
Y748000D03*
X12819Y751500D03*
X15012Y745563D03*
X17458Y737184D03*
X12419Y765261D03*
X14830Y763614D03*
X23000Y760000D03*
X12800Y870600D03*
X15600D03*
X13500Y862500D03*
X12864Y873315D03*
Y876315D03*
Y879315D03*
X15664D03*
Y876315D03*
Y873315D03*
X11700Y907753D03*
Y904753D03*
Y918753D03*
Y915753D03*
X32525Y904241D03*
Y907241D03*
X32825Y917841D03*
Y914841D03*
X12053Y937268D03*
Y934268D03*
X11700Y928753D03*
Y925753D03*
X32625Y925241D03*
Y928241D03*
X27587Y934815D03*
X31871Y961865D03*
X26791D03*
X29291D03*
X31871Y959365D03*
X29331D03*
X26791D03*
X14587Y958716D03*
X17087D03*
X19667D03*
Y956216D03*
X17127D03*
X14587D03*
X26990Y975034D03*
X25500Y977500D03*
X17500Y974500D03*
X28791Y976919D03*
X23702Y992261D03*
X20000Y989000D03*
X31791Y993000D03*
X26500Y997500D03*
X15275Y995500D03*
X15000Y1001300D03*
X16985Y1028800D03*
X19985D03*
Y1015800D03*
X16985D03*
X19985Y1012800D03*
X16985D03*
X22985Y1028800D03*
X25985D03*
Y1015800D03*
X22985D03*
X25985Y1012800D03*
X22985D03*
X24685Y1041800D03*
X18185Y1041900D03*
X21385D03*
X24685Y1038800D03*
X21385Y1038900D03*
X13492Y1049256D03*
Y1051756D03*
Y1046676D03*
X26000Y1062720D03*
X23000D03*
X20000D03*
X17000D03*
X14000D03*
X22000Y1104300D03*
X19000D03*
Y1107300D03*
X22000D03*
X25000D03*
X11000Y1215000D03*
X19500Y1239500D03*
X10241Y1234150D03*
X11000Y1239500D03*
X23500Y1237000D03*
X12150Y1227850D03*
X16017Y1323770D03*
X34927Y3006D03*
X54927D03*
X47399Y149664D03*
X44399D03*
Y152164D03*
X47399D03*
Y146864D03*
X44399D03*
X34380Y179643D03*
X47487Y171264D03*
X44487D03*
Y174264D03*
X47487D03*
X34380Y182643D03*
X34544Y189540D03*
X34480Y199243D03*
X50967Y246228D03*
X53967D03*
X48477Y233457D03*
X51477D03*
X54477D03*
X39167Y230228D03*
X42167D03*
X51456Y230214D03*
X54456D03*
X39167Y244728D03*
X42167D03*
X38880Y263169D03*
X55167Y259228D03*
X52167D03*
X55167Y272228D03*
Y256328D03*
X52167D03*
X38383Y280119D03*
X40472Y283287D03*
X55650Y280728D03*
X47561Y280228D03*
X53343Y301334D03*
X44500Y301500D03*
X50021Y313863D03*
X52561D03*
Y311363D03*
X50061D03*
X47481D03*
Y313863D03*
X37185Y316228D03*
X40185D03*
Y301728D03*
X37185D03*
X54926Y296651D03*
X53000Y345997D03*
Y348497D03*
Y350997D03*
X55700Y342500D03*
X53000Y364997D03*
Y367497D03*
Y369997D03*
X49689Y474203D03*
X56925Y503000D03*
Y528500D03*
Y508500D03*
X49250Y516750D03*
X37500Y520500D03*
Y512500D03*
X56925Y523500D03*
Y518500D03*
X57000Y538500D03*
X35484Y534075D03*
X47499Y649000D03*
X52977Y662650D03*
X56475Y654000D03*
X46950Y666500D03*
X45500Y646000D03*
X45240Y657000D03*
X56475Y672500D03*
X46950D03*
X52977Y681650D03*
X45240Y669500D03*
Y682000D03*
X33500Y694425D03*
X34000Y757000D03*
X37000Y756900D03*
X38900Y800200D03*
X52800Y813500D03*
X47813Y833013D03*
X48308Y877415D03*
Y880415D03*
Y883415D03*
X50808Y877415D03*
Y880415D03*
Y883415D03*
X48631Y964607D03*
Y962107D03*
X48731Y959507D03*
Y957007D03*
X42167Y958400D03*
X39167D03*
X48731Y972307D03*
Y974807D03*
X48631Y969707D03*
Y967207D03*
X42367Y972800D03*
X39367D03*
X51164Y988115D03*
Y985115D03*
X48664D03*
Y988115D03*
X40972Y1010059D03*
X38880Y989941D03*
X48492Y1006856D03*
X51164Y994115D03*
Y991115D03*
X48664D03*
Y994115D03*
X53000Y1026000D03*
X48005Y1012038D03*
X37555Y1027168D03*
X40555D03*
X53000Y1021500D03*
X40585Y1041300D03*
X37585D03*
X50561Y1038135D03*
X53061D03*
Y1040635D03*
X50521D03*
X47981D03*
Y1038135D03*
X55700Y1079289D03*
Y1075878D03*
X55701Y1071860D03*
Y1068449D03*
X55635Y1090665D03*
Y1094076D03*
X40500Y1164000D03*
X56000Y1203273D03*
X35517Y1323770D03*
X56017D03*
X61802Y25927D03*
X78400Y40200D03*
Y36700D03*
Y33200D03*
X68508Y50969D03*
X78400Y47200D03*
Y43700D03*
X68416Y63842D03*
X60475Y79692D03*
X61000Y84192D03*
X61300Y66900D03*
X69100Y76100D03*
X75173Y78000D03*
X68500Y70000D03*
X61500Y97500D03*
X71650Y94259D03*
Y111259D03*
X64025Y92575D03*
X65350Y102000D03*
X76000Y133500D03*
X71500Y130000D03*
X62716Y129542D03*
X58700Y110900D03*
X75500Y130000D03*
X76743Y116500D03*
X56967Y246228D03*
X58167Y259228D03*
X61167D03*
X58167Y272228D03*
X61167D03*
X64167D03*
X58167Y256328D03*
X61167D03*
X72500Y283771D03*
X64500Y287000D03*
X58561Y280728D03*
X56730Y278169D03*
X66561Y273985D03*
X61420Y299310D03*
X64765Y314512D03*
Y317012D03*
X62265Y314512D03*
X62225Y317012D03*
X59685D03*
Y314512D03*
X73300Y340600D03*
Y338100D03*
X74700Y346000D03*
Y351000D03*
Y348500D03*
X74428Y370500D03*
Y368000D03*
Y365500D03*
X68700Y400000D03*
X78500Y410000D03*
Y406000D03*
X65900Y413000D03*
X60475Y424728D03*
Y429228D03*
X62216Y412678D03*
X69018Y420378D03*
X77773Y420228D03*
X67000Y430500D03*
X71000Y427000D03*
X58500Y454500D03*
X60773Y443728D03*
Y457228D03*
X74979Y437559D03*
X79500Y449925D03*
X58500Y441000D03*
X65350Y447500D03*
X70500Y443500D03*
X65250Y470378D03*
X74500Y475000D03*
X68000Y463878D03*
X71300Y460000D03*
X57000Y483000D03*
X56925Y498000D03*
Y493000D03*
Y488000D03*
Y513500D03*
X78500Y512500D03*
Y504500D03*
X74626Y515080D03*
X79293Y523513D03*
X75650Y517770D03*
X56925Y533500D03*
X68345Y533265D03*
X76500Y531476D03*
X68500Y537075D03*
X72500Y541500D03*
X75396Y544500D03*
X73747Y570715D03*
X73500Y562200D03*
X74000Y608425D03*
X74857Y611575D03*
X56475Y641000D03*
X78457Y634010D03*
X78677Y637315D03*
X63070Y652400D03*
X56475Y647000D03*
Y660000D03*
X66400Y655400D03*
X65552Y645503D03*
X68000Y664000D03*
X56475Y666500D03*
Y679000D03*
Y685000D03*
X65475Y666500D03*
X65500Y671500D03*
X65475Y685000D03*
Y679000D03*
X69000Y669745D03*
X68000Y676500D03*
X59475Y688975D03*
X76500Y704000D03*
Y709500D03*
X60000Y696984D03*
X69350Y711940D03*
X68100Y721000D03*
X61500Y728500D03*
X70925Y732000D03*
X76475Y715000D03*
X74075Y732000D03*
X65570Y734500D03*
X74075Y721500D03*
Y726500D03*
X76475Y742500D03*
X70925Y749000D03*
X76500Y746500D03*
X58612Y740500D03*
X76725Y749500D03*
X66000Y776000D03*
X61576Y762200D03*
X58673Y775800D03*
X77816Y764764D03*
X78000Y782500D03*
X68694Y764764D03*
X69000Y771500D03*
X77400Y775000D03*
X68481Y800951D03*
X69018Y783764D03*
X62058Y801075D03*
X60000Y797925D03*
X71500Y805500D03*
X77000Y819000D03*
X61000Y810000D03*
X60773Y820614D03*
X71650Y821000D03*
X67993Y827764D03*
X65350Y818654D03*
X77000Y823500D03*
X68000Y804606D03*
X62216Y830875D03*
X77018Y836764D03*
X71410Y846500D03*
X75500Y852500D03*
X73000Y1010500D03*
X56150Y1007500D03*
X59268Y1007793D03*
X65367Y996400D03*
X62367D03*
X56367D03*
X59367D03*
X64108Y1006500D03*
X56245Y1004000D03*
X69802Y1006198D03*
X62500Y1025500D03*
X60185Y1043784D03*
X62725D03*
X65265D03*
Y1041284D03*
X62765D03*
X60185D03*
X76526Y1075845D03*
X76464Y1079181D03*
Y1072947D03*
X76526Y1069611D03*
X75860Y1064323D03*
X75893Y1061138D03*
X61029Y1064153D03*
Y1060742D03*
X76431Y1094565D03*
X76493Y1091229D03*
X62216Y1139950D03*
X77518Y1142650D03*
X68543Y1128650D03*
X77816D03*
X69018Y1147650D03*
X77773Y1147500D03*
X77518Y1138500D03*
X68686Y1139993D03*
X76500Y1162975D03*
X60475Y1152000D03*
X61500Y1160000D03*
X61000Y1172500D03*
X71150Y1165500D03*
X79000Y1157425D03*
Y1173425D03*
X64425Y1165500D03*
X64843Y1194000D03*
X79106Y1176575D03*
X75000Y1196500D03*
X57500Y1181000D03*
X74313Y1178559D03*
X64850Y1179000D03*
X76400Y1188100D03*
X73505Y1200075D03*
X76017Y1323770D03*
X85500Y40000D03*
Y36500D03*
Y33000D03*
X82975Y53333D03*
X84400Y64200D03*
X85500Y47000D03*
Y43500D03*
X99000Y61000D03*
X99883Y57500D03*
X87500Y83300D03*
X79500Y86925D03*
X80500Y74000D03*
X88802Y100198D03*
X86000Y92000D03*
X94430Y103830D03*
X91059Y94630D03*
X79500Y104425D03*
X88900Y119300D03*
X82500Y389500D03*
X84500Y404000D03*
X82500Y398000D03*
X79463Y429962D03*
X91500Y434000D03*
X82000Y415000D03*
X100835Y446500D03*
X91059Y452760D03*
X91593Y439000D03*
X95000Y462740D03*
X85500Y472975D03*
X86500Y481500D03*
X96502Y501930D03*
X84575Y487075D03*
X95184Y493787D03*
X98040Y506730D03*
X87500Y522800D03*
X98925Y515000D03*
X86500Y512500D03*
Y504500D03*
X98925Y524000D03*
Y512500D03*
X96275Y519750D03*
X98925Y534000D03*
X82000Y531476D03*
X87500D03*
X93000D03*
X84723Y532202D03*
X102075Y534000D03*
X84050Y555925D03*
X85000Y562148D03*
X100505Y561919D03*
X97000Y569153D03*
X90680Y561766D03*
X98780Y617000D03*
X99051Y635051D03*
X87500Y634700D03*
X88300Y639800D03*
X83300Y624100D03*
X103037Y624462D03*
X91532Y663261D03*
X95032Y660000D03*
X86000Y676000D03*
Y684000D03*
Y680000D03*
Y688000D03*
X101309Y675500D03*
X86000Y700000D03*
Y696000D03*
X93000Y731000D03*
X93025Y738000D03*
X93000Y745000D03*
X79975Y739975D03*
X99279Y781942D03*
X99500Y787000D03*
X83000Y804000D03*
X94000Y825740D03*
Y818500D03*
X101500Y824271D03*
X92950Y821707D03*
X83000Y810000D03*
X84000Y844950D03*
X99000Y848000D03*
X82000Y833575D03*
X104500Y834500D03*
X80000Y828500D03*
X99000Y853000D03*
X79500Y1134000D03*
X91000Y1173425D03*
X81000Y1193425D03*
X86000Y1176575D03*
X94730Y1173910D03*
X96017Y1323770D03*
X111522Y39800D03*
X114522D03*
X122917D03*
Y37300D03*
X111522Y44800D03*
X114522D03*
X111522Y47300D03*
Y49800D03*
X114522D03*
Y52300D03*
X111522D03*
X114522Y47300D03*
X111522Y42300D03*
X114522D03*
X122917Y49800D03*
Y47300D03*
Y44800D03*
Y42300D03*
X123500Y59500D03*
X118475Y83500D03*
X115918Y75650D03*
X112500Y76000D03*
X112000Y88700D03*
X122500Y102000D03*
X114500Y127000D03*
X123500Y115500D03*
X103000Y136500D03*
X127482Y286228D03*
X107000Y389500D03*
Y400425D03*
X113000Y394500D03*
X124378Y409308D03*
X107966Y408260D03*
X117500Y398500D03*
X112441Y418434D03*
X110500Y445000D03*
X106850Y441596D03*
X125200Y453800D03*
X113500Y476000D03*
X104500Y478500D03*
X122000Y463000D03*
X118490Y495330D03*
X124500Y485000D03*
X119000D03*
X113500D03*
X109000Y500000D03*
X105760Y493500D03*
X105815Y488500D03*
X105732Y496844D03*
X104500Y483425D03*
X126070Y493931D03*
X112070Y499790D03*
X109000Y485000D03*
X113500Y523000D03*
X111000Y506000D03*
X120000Y512500D03*
Y504500D03*
X108500Y512000D03*
X116000Y529500D03*
X108000Y539500D03*
X109000Y543500D03*
X111000Y555925D03*
X115788Y573787D03*
X125000Y562500D03*
X106977Y561919D03*
X121500Y557500D03*
X114000Y591000D03*
X120000Y581500D03*
X108601Y627084D03*
X118079Y639954D03*
X106000Y634500D03*
X124499Y660000D03*
X126185Y688915D03*
X123401Y669102D03*
X117500Y689900D03*
X119500Y707500D03*
X126500Y706500D03*
X118000Y696000D03*
X119500Y715500D03*
X115525Y731000D03*
X119000Y734000D03*
X125075Y715000D03*
X115525Y745000D03*
Y738000D03*
X112294Y754294D03*
X125352Y749277D03*
X114857Y741500D03*
X121536Y749253D03*
X121841Y775967D03*
X119836Y761664D03*
X107500Y782530D03*
X115563Y759063D03*
X125654Y772281D03*
X107365Y776004D03*
X118711Y797500D03*
X125500Y820114D03*
X125227Y815000D03*
X126000Y834500D03*
X120500Y845000D03*
X123000Y829114D03*
X117500Y857575D03*
X119500Y992000D03*
X121072Y1077500D03*
Y1075000D03*
Y1072500D03*
Y1094500D03*
Y1092000D03*
Y1097000D03*
X126500Y1129000D03*
X110000Y1128425D03*
X121000Y1131575D03*
Y1128425D03*
X112941Y1146240D03*
X124500Y1148575D03*
X109500Y1139500D03*
X123500Y1137500D03*
X118000Y1151575D03*
X123000Y1181000D03*
X125000Y1198000D03*
X116017Y1323770D03*
X146740Y3016D03*
X141748Y26922D03*
X125917Y39800D03*
Y37300D03*
X135014Y50977D03*
X125917Y49800D03*
Y47300D03*
Y44800D03*
Y42300D03*
X135500Y70441D03*
X142727Y79842D03*
X127000Y77500D03*
X142000Y74575D03*
X142727Y94000D03*
X134525Y107842D03*
X132350Y94273D03*
X142500Y103342D03*
X142000Y98842D03*
X138650Y94000D03*
X132500Y99000D03*
X141327Y115542D03*
X125500Y118000D03*
X135000Y120500D03*
X137449Y113340D03*
X135750Y132750D03*
X127500Y129500D03*
X141890Y246451D03*
X138198Y231944D03*
X140778D03*
X143358D03*
Y229444D03*
X140818D03*
X138238D03*
X133529Y265385D03*
X147393Y265728D03*
X136500Y261000D03*
X144482Y265728D03*
X139435Y266728D03*
X145982Y268287D03*
X147500Y278228D03*
X136482Y272471D03*
X127482Y289228D03*
X133482D03*
X130482D03*
X136482D03*
X133482Y286228D03*
X130482D03*
X136482D03*
X133482Y315228D03*
Y312228D03*
X130482Y315228D03*
Y312228D03*
X146482Y316228D03*
X127482Y315228D03*
X146482Y301728D03*
X130200Y339900D03*
Y337400D03*
X144600Y337100D03*
Y339828D03*
X128000Y348300D03*
X127900Y345100D03*
Y364300D03*
Y351800D03*
X127800Y370900D03*
X127900Y367900D03*
X141327Y398000D03*
X135245Y407228D03*
X136000Y429941D03*
X129314Y414545D03*
X145327Y416500D03*
X142727Y428000D03*
X132850Y421837D03*
X130500Y432500D03*
X139150Y420193D03*
Y429650D03*
X125500Y469600D03*
X135349Y468652D03*
X135000Y463000D03*
X129000Y468000D03*
X135500Y485024D03*
X130000Y485025D03*
X148000Y483000D03*
X134000Y501000D03*
X150575Y504500D03*
X144324Y498325D03*
X145193Y504232D03*
X141500Y516500D03*
X128000Y512500D03*
Y504500D03*
X144335Y509166D03*
X138532Y507500D03*
X150575Y534500D03*
X128500Y554925D03*
X135500Y562500D03*
X133491Y560490D03*
X131500Y634500D03*
X135000Y637500D03*
X150300Y645900D03*
X141900Y645410D03*
X134575Y659000D03*
X128000Y694500D03*
X133575Y692000D03*
X139150Y712500D03*
X136500Y728500D03*
X128065Y725566D03*
X146000Y729000D03*
X127983Y736234D03*
X136500Y742000D03*
X144827Y763510D03*
X129705Y777796D03*
X133900Y776000D03*
X129285Y781799D03*
X128500Y791500D03*
X132350Y793241D03*
X142727Y791500D03*
X141993Y800295D03*
X132370Y788872D03*
X128500Y786500D03*
X139650Y785905D03*
X139075Y801984D03*
X141327Y822814D03*
X134525Y815114D03*
X134800Y826614D03*
X138428Y806903D03*
X141088Y804709D03*
X133246Y811300D03*
X142999Y842350D03*
X148281Y838882D03*
X145600Y838100D03*
X146000Y854500D03*
X138278Y961865D03*
X140778D03*
X143358D03*
Y959365D03*
X140818D03*
X138278D03*
X142000Y977500D03*
X133529Y995306D03*
X136482Y1002392D03*
X147393Y995649D03*
X147229Y1004299D03*
X139435Y989500D03*
X144482Y995649D03*
X139435Y996649D03*
X145982Y998208D03*
X131882Y1012900D03*
X134882D03*
X131882Y1015900D03*
X134882D03*
X125882Y1012900D03*
X128882D03*
X125882Y1015900D03*
X128882D03*
X146482Y1028500D03*
X127182Y1055000D03*
Y1042000D03*
X133382Y1055000D03*
Y1042000D03*
Y1039000D03*
X130382Y1055000D03*
Y1042000D03*
Y1039000D03*
X146482Y1043000D03*
X126760Y1071023D03*
X126793Y1067838D03*
X143072Y1073000D03*
Y1075500D03*
Y1078000D03*
X141572Y1067900D03*
Y1070400D03*
X143072Y1092500D03*
Y1095000D03*
Y1097500D03*
X132175Y1117325D03*
X127000Y1143000D03*
X141649Y1141500D03*
X135500Y1143441D03*
X142088Y1131281D03*
X135800Y1138000D03*
X138650Y1149500D03*
X127000Y1157025D03*
X132350Y1156741D03*
X142727Y1151000D03*
X127000Y1166000D03*
X142500Y1161500D03*
X138650Y1165500D03*
X126360Y1185947D03*
X142500Y1183500D03*
X125440Y1175970D03*
X136800Y1194800D03*
X142500Y1176000D03*
X135000Y1197500D03*
X136017Y1323770D03*
X165799Y3002D03*
X148576Y146649D03*
X151576D03*
Y149149D03*
X148576D03*
X154576Y146649D03*
Y149149D03*
X149664Y174443D03*
Y171443D03*
Y168443D03*
Y165443D03*
X165164Y186143D03*
X164964Y196543D03*
X164864Y205443D03*
X168564Y217543D03*
Y214543D03*
X150500Y247000D03*
X153022Y232593D03*
X150482D03*
X155562D03*
X165562Y230593D03*
X163022D03*
X150482Y235093D03*
X152982D03*
X155562D03*
X165858Y244728D03*
X162858D03*
X165014Y268287D03*
X161105Y266081D03*
X155482Y266228D03*
X149000Y250000D03*
X149769Y283287D03*
X164947Y280728D03*
X156858Y280228D03*
X166499Y276483D03*
X169358Y286228D03*
X167858Y279310D03*
X149500Y295500D03*
X170358Y298858D03*
X156778Y311363D03*
Y313863D03*
X159318D03*
X161858D03*
Y311363D03*
X159358D03*
X149482Y316228D03*
Y301728D03*
X164296Y297723D03*
X162783Y301463D03*
X168982Y314512D03*
X171562D03*
X171522Y317012D03*
X168982D03*
X158858Y329228D03*
Y332228D03*
X149900Y346300D03*
Y349028D03*
Y351800D03*
Y364300D03*
Y370300D03*
Y367528D03*
X151635Y476202D03*
X154000Y471000D03*
X150575Y494500D03*
Y499500D03*
X150500Y489500D03*
X150575Y524500D03*
X170000Y504500D03*
X169000Y522000D03*
Y514000D03*
X150575Y519500D03*
Y509500D03*
X153725Y524500D03*
Y514500D03*
X169000Y535075D03*
X150500Y544500D03*
X150575Y539500D03*
Y529500D03*
X169000Y542075D03*
X167190Y529510D03*
X171977Y656850D03*
X166547Y663500D03*
X159051Y671661D03*
X167679Y674254D03*
X167642Y682217D03*
X169475Y706000D03*
X167060Y692500D03*
X171440Y708767D03*
X156962Y692037D03*
X169475Y733000D03*
Y713000D03*
Y720000D03*
X171586Y735683D03*
X171580Y716500D03*
X163925Y756500D03*
X169475Y747000D03*
Y740000D03*
X171500Y743500D03*
X167075Y756500D03*
X151300Y756400D03*
X149000Y854500D03*
X149500Y850500D03*
X152364Y890115D03*
Y893115D03*
Y896115D03*
X149864Y890115D03*
Y893115D03*
Y896115D03*
X162877Y910500D03*
Y913500D03*
Y931500D03*
Y934500D03*
Y921500D03*
Y924500D03*
X168177Y940100D03*
X153622Y962514D03*
X151082D03*
Y965014D03*
X153582D03*
X156162D03*
Y962514D03*
X167858Y961800D03*
X164858D03*
X168177Y943100D03*
X149658Y974968D03*
X164758Y976500D03*
X167758D03*
X151000Y981000D03*
X159000Y972500D03*
X164600Y998649D03*
X161581Y995673D03*
X149769Y1010059D03*
X164947Y1007500D03*
X167858D03*
X156858Y1007000D03*
X166358Y1004941D03*
X155482Y996149D03*
X169358Y1013000D03*
X161884Y1026048D03*
X170929Y1024429D03*
X149482Y1028500D03*
X162500Y1023000D03*
X149482Y1043000D03*
X156778Y1038135D03*
Y1040635D03*
X159318D03*
X161858D03*
Y1038135D03*
X159358D03*
X168982Y1043784D03*
X171522D03*
X171562Y1041284D03*
X168982D03*
X164000Y1171500D03*
X165500Y1229900D03*
X156017Y1323770D03*
X185799Y3002D03*
X193719Y157489D03*
X191219D03*
X192164Y164843D03*
X189664D03*
X192164Y167843D03*
X189664D03*
X192164Y170843D03*
X189664D03*
X192164Y173843D03*
X189664D03*
X186964Y189043D03*
Y186043D03*
Y199543D03*
Y196543D03*
X183582Y217228D03*
Y214228D03*
X186764Y208743D03*
Y205743D03*
X179358Y230328D03*
Y227328D03*
X182358Y230328D03*
Y227328D03*
X185358D03*
X185658Y243528D03*
X182658D03*
X179658D03*
X181258Y269528D03*
X184258D03*
X187258D03*
X178258D03*
X181067Y256528D03*
X184067D03*
X187067D03*
X178067D03*
X180967Y253728D03*
X177967D03*
X183967D03*
X186967D03*
X178811Y281071D03*
X175858Y273985D03*
X172905Y279728D03*
X174062Y314512D03*
Y317012D03*
X177458Y335828D03*
X180458D03*
X186458D03*
X183458D03*
X176858Y359790D03*
Y362290D03*
X185858Y359790D03*
X182858D03*
Y362290D03*
X185858D03*
X179858Y359790D03*
Y362290D03*
X189500Y512000D03*
X177000Y522000D03*
Y514000D03*
X191575Y518500D03*
Y524000D03*
X188516Y518310D03*
X179000Y531925D03*
X189250Y541750D03*
X191991Y536336D03*
X179000Y535075D03*
X191500Y529500D03*
X191259Y547500D03*
X182500Y641600D03*
X176000Y659500D03*
X175500Y651500D03*
X187050Y652000D03*
Y659500D03*
Y663500D03*
X182500Y688000D03*
X177500Y679500D03*
X175500Y672500D03*
X175475Y668500D03*
X181475Y713000D03*
X193475Y706000D03*
X179000Y694000D03*
X190300Y725200D03*
X187041Y730000D03*
X181475Y720000D03*
X192582Y733000D03*
X193000Y754500D03*
X191000Y756500D03*
X181475Y740000D03*
Y747000D03*
X189000Y758500D03*
X173200Y770800D03*
X193964Y887015D03*
Y890015D03*
Y893015D03*
Y896015D03*
X180264Y895915D03*
Y892915D03*
Y889915D03*
X193964Y899015D03*
X184377Y910500D03*
Y913500D03*
X180264Y898915D03*
X183177Y940100D03*
X184377Y931500D03*
Y934500D03*
Y921500D03*
Y924500D03*
X180658Y956100D03*
X186658D03*
Y952900D03*
X180658D03*
X183758Y956200D03*
Y953000D03*
X183177Y943100D03*
X180658Y969000D03*
X186658D03*
X183758Y969100D03*
X182285Y982200D03*
X179285D03*
X188285D03*
X185285D03*
X178811Y1007843D03*
X175858Y1000757D03*
X172905Y1006500D03*
X187658Y995000D03*
Y998000D03*
X184658Y995000D03*
Y998000D03*
X181658Y995000D03*
Y998000D03*
X190158Y995000D03*
Y998000D03*
X174062Y1043784D03*
Y1041284D03*
X190358Y1062764D03*
X187358D03*
X184358D03*
X181358D03*
Y1060064D03*
X184358D03*
X187358D03*
X190358D03*
X186458Y1103662D03*
X183458D03*
X180458D03*
X186458Y1106662D03*
X180458D03*
X183458D03*
X192500Y1215000D03*
X192000Y1240500D03*
X182741Y1235150D03*
X183500Y1240500D03*
X182600Y1228850D03*
X176017Y1323770D03*
X194471Y1321882D03*
X199120Y9903D03*
X200536Y29059D03*
Y49059D03*
Y69059D03*
Y109059D03*
Y89059D03*
Y129059D03*
Y149059D03*
Y169059D03*
Y189059D03*
Y209059D03*
Y249059D03*
Y229059D03*
Y269059D03*
Y289059D03*
Y309059D03*
Y329059D03*
Y349059D03*
Y369059D03*
Y409059D03*
Y389059D03*
Y429059D03*
Y449059D03*
Y469059D03*
Y489059D03*
X195000Y490500D03*
X195500Y495000D03*
Y497500D03*
X200536Y509059D03*
Y549059D03*
Y529059D03*
Y569059D03*
Y589059D03*
Y609059D03*
Y629059D03*
Y649059D03*
Y669059D03*
Y709059D03*
Y689059D03*
Y729059D03*
X195000Y752500D03*
X200536Y749059D03*
Y769059D03*
Y789059D03*
Y809059D03*
Y849059D03*
Y829059D03*
Y869059D03*
Y889059D03*
Y909059D03*
Y929059D03*
Y947059D03*
Y969059D03*
Y1009059D03*
Y989059D03*
Y1029059D03*
Y1049059D03*
Y1069059D03*
Y1089059D03*
Y1109059D03*
Y1149059D03*
Y1129059D03*
Y1169059D03*
Y1189059D03*
Y1209059D03*
Y1229059D03*
X195500Y1220000D03*
Y1222500D03*
X200536Y1249059D03*
Y1289059D03*
Y1269059D03*
Y1309059D03*
G54D31*
X27000Y531016D03*
X19000D03*
X23000D03*
X17000Y989516D03*
X33000Y531016D03*
X64543Y54858D03*
X77000Y87016D03*
Y104516D03*
X66561Y279244D03*
X77000Y432516D03*
Y450016D03*
X76500Y526016D03*
X71000Y534016D03*
X76500D03*
X68000Y565016D03*
X75000D03*
X78500Y608516D03*
X72000Y628516D03*
X68000D03*
X77000Y800516D03*
Y813516D03*
X67061Y1006016D03*
X76500Y1157516D03*
Y1173516D03*
X96000Y53216D03*
X91500D03*
Y109516D03*
Y467516D03*
X82000Y526016D03*
X93000Y534016D03*
X87500D03*
X82000D03*
X101000Y556016D03*
X91000D03*
X95500D03*
X80000D03*
X93000Y565016D03*
X101000D03*
X85000D03*
X80800Y640016D03*
X80900Y628516D03*
X91500Y830516D03*
Y1193516D03*
X106500Y53216D03*
X102500D03*
X103000Y130016D03*
X113500Y400516D03*
X115000Y420516D03*
X106500Y500516D03*
X113500Y487516D03*
X119000D03*
X116000Y524016D03*
X106000Y531516D03*
X110000D03*
X114500Y556016D03*
X124500Y555016D03*
X107500Y556016D03*
X124500Y565016D03*
X107500D03*
X117000D03*
X117500Y765516D03*
X114500Y785516D03*
X115500Y1148516D03*
X118500Y1128516D03*
X143500Y55016D03*
X135500Y487516D03*
X131500Y555016D03*
X135500D03*
Y565016D03*
X131500D03*
X129000Y1129016D03*
X166500Y532016D03*
Y539016D03*
X161000Y854516D03*
X175858Y279244D03*
X171500Y532016D03*
Y539016D03*
X176500Y532016D03*
X175858Y1006016D03*
G54D13*
X9425Y124000D03*
X12575D03*
X25075D03*
X21925D03*
X16575Y393000D03*
X13425D03*
X15075Y487000D03*
X11925D03*
X27575D03*
X24425D03*
X11925Y491000D03*
X15075D03*
X17075Y1215000D03*
X13925D03*
X53775Y500500D03*
Y495500D03*
Y490500D03*
Y485500D03*
X53850Y480500D03*
X53775Y526000D03*
Y521000D03*
Y516000D03*
Y511000D03*
Y506000D03*
X53850Y536000D03*
X53775Y531000D03*
X54925Y805000D03*
Y816000D03*
Y1168500D03*
Y1156000D03*
Y1160000D03*
Y1178500D03*
X36075Y1235500D03*
X32925D03*
X65425Y81000D03*
X68575D03*
X65425Y98000D03*
X68575D03*
X75075Y406000D03*
X71925D03*
X64925Y427000D03*
X68075D03*
X64925Y443500D03*
X68075D03*
X58425Y475000D03*
X61575D03*
X60075Y500500D03*
X56925D03*
X60075Y495500D03*
X56925D03*
X60075Y490500D03*
X56925D03*
X60075Y485500D03*
X56925D03*
X60150Y480500D03*
X57000D03*
X56925Y500500D03*
Y495500D03*
Y490500D03*
Y485500D03*
X57000Y480500D03*
X60075Y526000D03*
X56925D03*
X60075Y521000D03*
X56925D03*
X60075Y516000D03*
X56925D03*
X60075Y511000D03*
X56925D03*
X60075Y506000D03*
X56925D03*
Y526000D03*
Y521000D03*
Y516000D03*
Y511000D03*
Y506000D03*
X60150Y536000D03*
X57000D03*
X60075Y531000D03*
X56925D03*
X57000Y536000D03*
X56925Y531000D03*
X74075Y746500D03*
X70925D03*
X58075Y805000D03*
Y816000D03*
X71425Y823500D03*
X74575D03*
X64925Y807500D03*
X68075D03*
X66925Y834000D03*
X70075D03*
X75075Y1138500D03*
X71925D03*
X58075Y1168500D03*
Y1156000D03*
Y1160000D03*
X64425Y1168000D03*
X67575D03*
X58075Y1178500D03*
X64425Y1184000D03*
X67575D03*
X72575Y1196500D03*
X69425D03*
X98925Y527000D03*
X120425Y144500D03*
X123575D03*
X124425Y429000D03*
X102075Y527000D03*
X129925Y65000D03*
X133075D03*
X138575Y81000D03*
X135425D03*
X138575Y97000D03*
X135425D03*
X127925Y114000D03*
X131075D03*
X129425Y403728D03*
X132575D03*
X127575Y429000D03*
X139575Y424500D03*
X136425D03*
X128425Y465500D03*
X131575D03*
X147350Y487000D03*
X147425Y492000D03*
Y497000D03*
Y502000D03*
Y507000D03*
Y512000D03*
Y517000D03*
Y522000D03*
Y527000D03*
Y532000D03*
Y537000D03*
X147350Y542000D03*
X128425Y762000D03*
X131575D03*
X148075Y796500D03*
X144925D03*
X148075Y786500D03*
X144925D03*
X139075Y790800D03*
X135925D03*
X128425Y824614D03*
X131575D03*
X145425Y1146400D03*
Y1156000D03*
Y1165000D03*
Y1169500D03*
X139075Y1170000D03*
X135925D03*
X139075Y1154000D03*
X135925D03*
X128425Y1188000D03*
X131575D03*
X150500Y487000D03*
X150575Y492000D03*
Y497000D03*
Y502000D03*
X153650Y487000D03*
X150500D03*
X153725Y492000D03*
X150575D03*
X153725Y497000D03*
X150575D03*
X153725Y502000D03*
X150575D03*
Y507000D03*
Y512000D03*
Y517000D03*
Y522000D03*
X153725Y507000D03*
X150575D03*
X153725Y512000D03*
X150575D03*
X153725Y517000D03*
X150575D03*
X153725Y522000D03*
X150575D03*
Y527000D03*
Y532000D03*
Y537000D03*
X150500Y542000D03*
X153725Y527000D03*
X150575D03*
X153725Y532000D03*
X150575D03*
X153725Y537000D03*
X150575D03*
X153650Y542000D03*
X150500D03*
X148575Y1146400D03*
Y1156000D03*
Y1165000D03*
Y1169500D03*
X190425Y124500D03*
X193575D03*
X177925D03*
X181075D03*
X186925Y490000D03*
X190075D03*
X186425Y1215000D03*
X189575D03*
X178075Y1236500D03*
X174925D03*
G54D40*
X50150Y385441D03*
X43850Y388000D03*
X50150Y390559D03*
X71650Y86441D03*
X65350Y106000D03*
X71650Y108559D03*
Y103441D03*
X65350Y89000D03*
X71650Y91559D03*
Y432441D03*
X65350Y451500D03*
X71650Y454059D03*
Y448941D03*
X65350Y435000D03*
X71650Y437559D03*
X65350Y799500D03*
X71650Y802059D03*
Y796941D03*
X65350Y815500D03*
X71650Y818059D03*
Y812941D03*
X71150Y1173441D03*
X64850Y1160000D03*
X71150Y1162559D03*
Y1157441D03*
X64850Y1176000D03*
X71150Y1178559D03*
X88350Y123500D03*
X94650Y126059D03*
Y120941D03*
X80850Y848500D03*
X87150Y845941D03*
Y851059D03*
X114650Y131500D03*
X108350Y128941D03*
Y134059D03*
X138650Y73000D03*
X132350Y70441D03*
Y75559D03*
Y86441D03*
X138650Y89000D03*
X132350Y91559D03*
X139150Y416500D03*
X132850Y413941D03*
Y419059D03*
X139150Y432500D03*
X132850Y429941D03*
Y435059D03*
X133350Y780141D03*
X139650Y782700D03*
X133350Y785259D03*
X138650Y798500D03*
X132350Y795941D03*
Y801059D03*
X138650Y1146000D03*
X132350Y1143441D03*
Y1148559D03*
X138650Y1162000D03*
X132350Y1159441D03*
Y1164559D03*
X153850Y386441D03*
X160150Y389000D03*
X153850Y391559D03*
X166850Y853441D03*
Y858559D03*
X173150Y856000D03*
G54D22*
X22780Y155131D03*
X27480Y880000D03*
X57820Y155131D03*
X46023Y358300D03*
X62520Y880000D03*
X46023Y1085072D03*
X81063Y358300D03*
Y1085072D03*
X121380Y358100D03*
X119980Y1085072D03*
X145634Y155131D03*
X141880Y883400D03*
X155020Y1085072D03*
X156420Y358100D03*
X176920Y883400D03*
X180674Y155131D03*
G54D23*
X26516Y255500D03*
X19307Y262728D03*
X22516Y251500D03*
X15016Y641000D03*
Y660000D03*
Y654000D03*
Y645500D03*
Y686000D03*
Y680500D03*
Y672500D03*
Y666500D03*
X13516Y715000D03*
Y727000D03*
X20016Y974500D03*
X14016Y1239500D03*
X54559Y56342D03*
X55016Y79692D03*
X32807Y263728D03*
X43577Y277728D03*
X49516Y289000D03*
X54559Y401378D03*
X55016Y424728D03*
X51016Y641000D03*
Y660000D03*
Y654000D03*
Y647000D03*
Y685000D03*
Y679000D03*
Y672500D03*
Y666500D03*
X34516Y727500D03*
X54559Y764764D03*
X55016Y788114D03*
X44077Y1004500D03*
X32807Y990500D03*
X54559Y1128650D03*
X55016Y1152000D03*
X69016Y641000D03*
Y657500D03*
Y651500D03*
Y647000D03*
Y685000D03*
Y679000D03*
Y672500D03*
Y666500D03*
X71016Y704000D03*
Y709500D03*
Y719000D03*
Y724000D03*
Y715000D03*
Y742500D03*
Y751500D03*
X63516Y778500D03*
X56516Y1024000D03*
Y1016000D03*
X88516Y92000D03*
X99016Y478500D03*
Y483425D03*
Y498500D03*
Y488500D03*
Y517500D03*
X80516Y676000D03*
Y684000D03*
Y692000D03*
Y700000D03*
X99016Y706500D03*
Y711000D03*
X95516Y731000D03*
Y738000D03*
Y745000D03*
X104600Y81551D03*
X112516Y667500D03*
Y671500D03*
Y675500D03*
Y679500D03*
Y683500D03*
Y687500D03*
X106516Y706500D03*
Y711000D03*
X112516Y693000D03*
X106516Y731000D03*
Y718000D03*
Y738000D03*
Y745000D03*
X118016Y752000D03*
X145516Y107842D03*
Y98842D03*
X137016Y107842D03*
X138516Y126842D03*
X128016Y118000D03*
X143016Y253000D03*
X142998Y262728D03*
X129516Y408000D03*
X145516Y442728D03*
Y451728D03*
X128516Y456728D03*
X137016Y451728D03*
X137516Y470728D03*
X129516Y728500D03*
X145516Y806114D03*
Y815114D03*
X128516Y820114D03*
X137016Y815114D03*
X137516Y834114D03*
X146016Y985000D03*
X142998Y992649D03*
X145516Y1160500D03*
Y1178500D03*
X128516Y1183500D03*
X137516Y1197500D03*
X156498Y263728D03*
X152874Y277728D03*
X159016Y288000D03*
X170016Y663500D03*
Y659500D03*
Y651500D03*
X164016Y706000D03*
Y733000D03*
X149016Y729000D03*
X152874Y1004500D03*
X156498Y993649D03*
X165016Y1025500D03*
Y1017500D03*
X188516Y515500D03*
Y521000D03*
Y532000D03*
Y526500D03*
X176016Y720000D03*
Y713000D03*
Y747000D03*
Y740000D03*
X186516Y1240500D03*
G54D32*
X27000Y533983D03*
X19000D03*
X23000D03*
X17000Y992483D03*
X33000Y533983D03*
X64543Y57825D03*
X77000Y107483D03*
Y89983D03*
X66561Y282211D03*
X77000Y452983D03*
Y435483D03*
X71000Y536983D03*
X76500D03*
Y528983D03*
X68000Y567983D03*
X75000D03*
X78500Y611483D03*
X72000Y631483D03*
X68000D03*
X77000Y803483D03*
Y816483D03*
X67061Y1008983D03*
X76500Y1160483D03*
Y1176483D03*
X96000Y56183D03*
X91500D03*
Y112483D03*
Y470483D03*
X93000Y536983D03*
X87500D03*
X82000D03*
Y528983D03*
X101000Y558983D03*
X91000D03*
X95500D03*
X80000D03*
X93000Y567983D03*
X101000D03*
X85000D03*
X80900Y631483D03*
X80800Y642983D03*
X91500Y833483D03*
Y1196483D03*
X106500Y56183D03*
X102500D03*
X103000Y132983D03*
X113500Y403483D03*
X115000Y423483D03*
X113500Y490483D03*
X119000D03*
X106500Y503483D03*
X106000Y534483D03*
X110000D03*
X116000Y526983D03*
X114500Y558983D03*
X124500Y557983D03*
X107500Y558983D03*
X124500Y567983D03*
X107500D03*
X117000D03*
X117500Y768483D03*
X114500Y788483D03*
X118500Y1131483D03*
X115500Y1151483D03*
X143500Y57983D03*
X135500Y490483D03*
X131500Y557983D03*
X135500D03*
Y567983D03*
X131500D03*
X129000Y1131983D03*
X166500Y534983D03*
Y541983D03*
X161000Y857483D03*
X175858Y282211D03*
X171500Y534983D03*
Y541983D03*
X176500Y534983D03*
X175858Y1008983D03*
G54D41*
X37000Y384600D03*
Y390400D03*
X72000Y463100D03*
Y468900D03*
X82300Y121100D03*
Y126900D03*
X122500Y105100D03*
Y110900D03*
X185000Y868100D03*
Y873900D03*
G54D50*
X85941Y104740D03*
X91059D03*
Y97260D03*
X88500D03*
X85941D03*
X91059Y455260D03*
X88500D03*
X85941D03*
Y462740D03*
X91059D03*
X85941Y825740D03*
X91059D03*
Y818260D03*
X88500D03*
X85941D03*
Y1188740D03*
X91059D03*
Y1181260D03*
X88500D03*
X85941D03*
X118559Y71260D03*
X113441D03*
Y78740D03*
X116000D03*
X118559D03*
X117559Y408260D03*
X112441D03*
Y415740D03*
X115000D03*
X117559D03*
X117059Y773260D03*
X111941D03*
Y780740D03*
X114500D03*
X117059D03*
X118059Y1136260D03*
X112941D03*
Y1143740D03*
X115500D03*
X118059D03*
G54D14*
X9425Y129000D03*
X9400Y241516D03*
X10500Y274500D03*
X11800Y284000D03*
X11433Y983048D03*
X17200Y124000D03*
X25075Y119000D03*
X34544Y192540D03*
X34480Y202243D03*
X29191Y210428D03*
X22170Y246150D03*
X14791Y247715D03*
X29390Y246960D03*
X16873Y257024D03*
X27987Y264636D03*
X21500Y267500D03*
X32716Y273500D03*
X24000Y276000D03*
X18185Y312228D03*
X27185D03*
X17500Y361728D03*
X26500D03*
X29820Y379910D03*
X24880Y480480D03*
X19700Y487000D03*
X21320Y506500D03*
X16580Y526220D03*
X22100Y526120D03*
X21070Y636050D03*
X19850Y691868D03*
X21500Y727000D03*
X22000Y718000D03*
X29000Y728000D03*
X19820Y754600D03*
X27587Y937815D03*
X14791Y976000D03*
X27886Y972134D03*
X23009Y995491D03*
X30522Y1000288D03*
X18185Y1038900D03*
X25000Y1104300D03*
X25060Y1215540D03*
X50000Y63842D03*
X48100Y56342D03*
X48184Y73876D03*
X48313Y68687D03*
X49985Y81177D03*
X49500Y109600D03*
X50000Y97500D03*
X51400Y120342D03*
X36880Y249217D03*
X42309Y251270D03*
X48456Y230214D03*
X41864Y265636D03*
X44500Y272767D03*
X40500Y295500D03*
X51956Y283826D03*
X45500Y298350D03*
X52000Y298528D03*
X57430Y298520D03*
X49800Y401378D03*
X46500Y416000D03*
Y423868D03*
Y432116D03*
X50000Y428000D03*
X49200Y457228D03*
X46500Y451614D03*
Y463378D03*
X48217Y480500D03*
X41196Y489754D03*
X49023Y490500D03*
X45953Y495500D03*
X48872Y500500D03*
X44140Y505060D03*
X48970Y507700D03*
X47140Y512860D03*
X48500Y519850D03*
X49120Y526000D03*
X43450Y528170D03*
X47865Y534580D03*
X54160Y689760D03*
X49400Y772264D03*
X49800Y764764D03*
X47100Y789700D03*
X46500Y783764D03*
X46900Y795128D03*
X48000Y801075D03*
X50900Y826998D03*
X46500Y820614D03*
X46900Y806500D03*
X35259Y968798D03*
X38500Y977199D03*
X40500Y995000D03*
X39061Y1005000D03*
X51852Y1012249D03*
X42000Y1023000D03*
X44100Y1027850D03*
X50000Y1023000D03*
X46500Y1147650D03*
X53900Y1142766D03*
X46409Y1136709D03*
X49400Y1153000D03*
X49764Y1175063D03*
X47000Y1166500D03*
X48200Y1160000D03*
X50900Y1190150D03*
X46500Y1184000D03*
X37200Y1215500D03*
X40700Y1235600D03*
X73877Y80768D03*
X81400Y95000D03*
X67310Y114250D03*
X71689Y302000D03*
X64561Y298446D03*
X76682Y426000D03*
X80650Y457650D03*
X65300Y480500D03*
X68930Y485500D03*
X65300Y490500D03*
X70460Y495120D03*
X64700Y498190D03*
X69290Y500790D03*
X65479Y504809D03*
X64800Y510030D03*
X66290Y515220D03*
X64820Y520300D03*
X64710Y525630D03*
X73500Y521000D03*
X64945Y534505D03*
X61710Y559000D03*
X79930Y579000D03*
X72899Y582500D03*
X80400Y621200D03*
X73285Y616764D03*
X64480Y636220D03*
X72000Y623700D03*
X60500Y693500D03*
X65610Y700000D03*
X60260Y704661D03*
X65920Y708260D03*
X65100Y725200D03*
X65870Y715000D03*
X65087Y747089D03*
X80500Y822500D03*
X72000Y1013500D03*
X74000Y1026000D03*
X66000Y1025000D03*
X64231Y1115268D03*
X80000Y1151500D03*
X79991Y1181260D03*
X93075Y72000D03*
X93312Y132925D03*
X89169Y401350D03*
X93648Y482621D03*
X93477Y490571D03*
X90990Y521240D03*
X92194Y572807D03*
X81442Y573302D03*
X89610Y580015D03*
X99500Y578500D03*
X87977Y623045D03*
X95732Y622114D03*
X101284Y671500D03*
X101124Y715876D03*
X95980Y805970D03*
X81500Y789000D03*
X95920Y813575D03*
X102500Y979500D03*
X82000Y1123500D03*
X97760Y1193780D03*
X112500Y65500D03*
X110425Y114000D03*
X124000Y150630D03*
X115680Y139670D03*
X127482Y312228D03*
X118500Y403500D03*
X110000Y392500D03*
X122100Y418100D03*
X127000Y446000D03*
X122500Y473500D03*
X122070Y495240D03*
X114913Y495488D03*
X106740Y508780D03*
X110000Y526490D03*
X107320Y519640D03*
X109000Y573500D03*
X123603Y575972D03*
X107000Y621000D03*
X115500Y622000D03*
X124323Y621748D03*
X123608Y664209D03*
X124830Y679870D03*
X120400Y670820D03*
X124820Y674220D03*
X120305Y677055D03*
X120550Y689650D03*
X121920Y684380D03*
X112339Y701350D03*
X119975Y723132D03*
X121500Y809000D03*
X122000Y838500D03*
X127182Y1039000D03*
X120300Y1148500D03*
X123000Y1173500D03*
X116737Y1162763D03*
X112281Y1194600D03*
X138700Y57700D03*
X135700Y102300D03*
X128000Y251000D03*
X137495Y248875D03*
X142400Y269800D03*
X133963Y255892D03*
X129370Y495230D03*
X141500Y487500D03*
X136000Y498500D03*
X141390Y496350D03*
X142060Y522960D03*
X133470Y527000D03*
X139020Y514480D03*
X136560Y519360D03*
X135420Y537000D03*
X139890Y542000D03*
X142330Y532000D03*
X131875Y623376D03*
X139350Y694910D03*
X129112Y978769D03*
X136505Y986470D03*
X138605Y977649D03*
X146644Y1007363D03*
X149500Y1023000D03*
X157000Y52982D03*
X156950Y76050D03*
X156782Y87719D03*
X157000Y101000D03*
X153200Y107842D03*
X157000Y93000D03*
X154124Y124576D03*
X156600Y114600D03*
X165164Y189143D03*
X164964Y199543D03*
X164864Y208443D03*
X152500Y249501D03*
X161200Y251200D03*
X159430Y244830D03*
X161128Y283003D03*
X152420Y296500D03*
X167000Y296310D03*
X160777Y275688D03*
X160000Y298500D03*
X154500Y410000D03*
X157496Y400176D03*
X155598Y426934D03*
X155309Y435073D03*
X155686Y418730D03*
X153324Y449248D03*
X157000Y455738D03*
Y442728D03*
Y468500D03*
X152600Y463612D03*
X162220Y505480D03*
X166630Y502000D03*
X159680Y497000D03*
X165300Y492000D03*
X159830Y487000D03*
X158870Y525510D03*
X158410Y516230D03*
X158570Y509929D03*
X159730Y539520D03*
X158790Y533400D03*
X164152Y657373D03*
X165103Y678233D03*
X164572Y669102D03*
X165032Y685986D03*
X161312Y696884D03*
X171087Y724838D03*
X172000Y751500D03*
X173800Y759446D03*
X152266Y773430D03*
X155800Y779425D03*
X156500Y787700D03*
X157000Y801500D03*
X154168Y812669D03*
X155800Y826998D03*
X157000Y819114D03*
X153300Y806114D03*
X156900Y834114D03*
X154502Y971101D03*
X152823Y978573D03*
X160732Y977966D03*
X164337Y1002475D03*
X159500Y1023000D03*
X153150Y1028430D03*
X152600Y1135000D03*
X157000Y1146925D03*
Y1155000D03*
Y1164500D03*
X153200Y1169500D03*
X157000Y1182500D03*
X157500Y1197500D03*
X152600Y1190384D03*
X155286Y1175985D03*
X162800Y1215277D03*
X162400Y1229900D03*
X193575Y129925D03*
X185700Y124500D03*
Y112900D03*
X185358Y230328D03*
X173858Y298500D03*
X183500Y299500D03*
X188800Y408300D03*
X183610Y398050D03*
X185700Y476200D03*
X194000Y550000D03*
X182730Y535090D03*
X183720Y529289D03*
X176350Y540120D03*
X187500Y643500D03*
X180500Y684500D03*
X179000Y676500D03*
X187925Y701000D03*
X181000Y696500D03*
X184425Y738000D03*
X193308Y839608D03*
X177021Y1016322D03*
X182058Y1022519D03*
X173858Y1025500D03*
G54D60*
G01X84850Y491350D02*
X85650Y492150D01*
Y500626D01*
G01X83555Y493394D02*
X84075Y493914D01*
Y500626D01*
G01X82500Y495592D02*
Y500626D01*
G01X77486Y495500D02*
X78884D01*
X80925Y497541D01*
Y500626D01*
G01X76809Y498051D02*
X78679D01*
X79350Y498722D01*
Y500626D01*
G01X75902Y500550D02*
X77700D01*
X77776Y500626D01*
G01X75868Y523685D02*
X80925Y518628D01*
Y516374D01*
G01X68970Y503450D02*
X69296Y503776D01*
X74626D01*
G01X67128Y508039D02*
X69817Y505350D01*
X74626D01*
G01Y506925D02*
X71001D01*
X66903Y511023D01*
Y512164D01*
G01X67094Y518714D02*
X67968Y517840D01*
X69102Y515101D01*
Y511384D01*
X69364Y511122D01*
Y511120D01*
X71984Y508500D01*
X74626D01*
G01Y510075D02*
X72674D01*
X70702Y512047D01*
Y516703D01*
X69531Y519530D01*
X68721Y520340D01*
G01X66000Y528554D02*
X67583Y524733D01*
X71022Y521294D01*
Y520896D01*
X72326Y517747D01*
Y512584D01*
X73260Y511650D01*
X74626D01*
G01X73500Y521000D02*
X74312D01*
X78161Y519406D01*
X79350Y518217D01*
Y516374D01*
G01X76660D02*
X77776D01*
G01X90374Y508500D02*
X93285D01*
X96502Y505283D01*
Y503337D01*
G01X89889Y499832D02*
Y501367D01*
X90374Y501852D01*
Y503776D01*
G01X92901Y501682D02*
Y504950D01*
X92501Y505350D01*
X90374D01*
G01X94622Y500211D02*
Y505194D01*
X92891Y506925D01*
X90374D01*
G01Y510075D02*
X94695D01*
X96770Y508000D01*
G01X89787Y520475D02*
X87224Y517912D01*
Y516374D01*
G01X85650D02*
Y519015D01*
X87500Y520865D01*
Y521736D01*
G01X84075Y516374D02*
Y520479D01*
G01X82500Y516374D02*
Y519928D01*
X80613Y521815D01*
G01X90374Y511650D02*
X92650D01*
X93500Y512500D01*
X94500D01*
G01X122070Y495240D02*
X122425Y496097D01*
Y500626D01*
G01X117000Y497500D02*
X117500Y498000D01*
X118500D01*
X119276Y498776D01*
Y500626D01*
G01X119454Y496046D02*
X120850Y497442D01*
Y500626D01*
G01X124000D02*
Y497490D01*
X124700Y495800D01*
G01X112500Y504000D02*
X113850Y505350D01*
X116126D01*
G01Y508500D02*
X110000D01*
G01X116126Y506925D02*
X111925D01*
X111000Y506000D01*
G01X112809Y516173D02*
X114001Y514981D01*
Y514135D01*
X114912Y513224D01*
X116126D01*
G01Y511650D02*
X113454D01*
X113000Y512104D01*
G01X109500Y511000D02*
X110425Y510075D01*
X116126D01*
G01X121338Y523237D02*
Y522105D01*
X122425Y521018D01*
Y516374D01*
G01X119038Y523237D02*
Y522142D01*
X120850Y520330D01*
Y516374D01*
G01X123638Y523237D02*
Y522068D01*
X124000Y521706D01*
Y516374D01*
G01X128000Y495500D02*
X125575Y497925D01*
Y500626D01*
G01X127150D02*
Y498970D01*
X128560Y497560D01*
X130880D01*
G01X131110Y500626D02*
X128724D01*
G01X137133Y502119D02*
X133902Y505350D01*
X131874D01*
G01Y506925D02*
X135724D01*
X137479Y505170D01*
G01X128858Y521485D02*
X127150Y519777D01*
Y516374D01*
G01X131874Y511650D02*
X135378D01*
G01X125938Y523237D02*
Y522068D01*
X125575Y521705D01*
Y516374D01*
G01X131874Y513224D02*
X134607D01*
X135574Y514191D01*
G01X130080Y519360D02*
X128724Y518004D01*
Y516374D01*
G01X131874Y508500D02*
X137532D01*
X138532Y507500D01*
G01X139925Y509500D02*
X139350Y510075D01*
X131874D01*
G54D24*
X29483Y255500D03*
X22274Y262728D03*
X25483Y251500D03*
X17983Y641000D03*
Y660000D03*
Y654000D03*
Y645500D03*
Y686000D03*
Y680500D03*
Y672500D03*
Y666500D03*
X16483Y715000D03*
Y727000D03*
X22983Y974500D03*
X16983Y1239500D03*
X35774Y263728D03*
X46544Y277728D03*
X52483Y289000D03*
X53983Y641000D03*
Y660000D03*
Y654000D03*
Y647000D03*
Y685000D03*
Y679000D03*
Y672500D03*
Y666500D03*
X37483Y727500D03*
X47044Y1004500D03*
X35774Y990500D03*
X57526Y56342D03*
X57983Y79692D03*
X57526Y401378D03*
X57983Y424728D03*
X71983Y641000D03*
Y657500D03*
Y651500D03*
Y647000D03*
Y685000D03*
Y679000D03*
Y672500D03*
Y666500D03*
X73983Y704000D03*
Y709500D03*
Y719000D03*
Y724000D03*
Y715000D03*
Y742500D03*
Y751500D03*
X57526Y764764D03*
X66483Y778500D03*
X57983Y788114D03*
X59483Y1024000D03*
Y1016000D03*
X57526Y1128650D03*
X57983Y1152000D03*
X91483Y92000D03*
X83483Y676000D03*
Y684000D03*
Y692000D03*
Y700000D03*
X98483Y731000D03*
Y738000D03*
Y745000D03*
X107567Y81551D03*
X101983Y478500D03*
Y483425D03*
Y498500D03*
Y488500D03*
Y517500D03*
X115483Y667500D03*
Y671500D03*
Y675500D03*
Y679500D03*
Y683500D03*
Y687500D03*
X109483Y706500D03*
Y711000D03*
X115483Y693000D03*
X101983Y706500D03*
Y711000D03*
X109483Y731000D03*
Y718000D03*
Y738000D03*
Y745000D03*
X120983Y752000D03*
X139983Y107842D03*
X141483Y126842D03*
X130983Y118000D03*
X145983Y253000D03*
X145965Y262728D03*
X132483Y408000D03*
X131483Y456728D03*
X139983Y451728D03*
X140483Y470728D03*
X132483Y728500D03*
X131483Y820114D03*
X139983Y815114D03*
X140483Y834114D03*
X145965Y992649D03*
X131483Y1183500D03*
X140483Y1197500D03*
X148483Y107842D03*
Y98842D03*
X159465Y263728D03*
X155841Y277728D03*
X161983Y288000D03*
X148483Y442728D03*
Y451728D03*
X166983Y706000D03*
Y733000D03*
X151983Y729000D03*
X148483Y806114D03*
Y815114D03*
X148983Y985000D03*
X155841Y1004500D03*
X159465Y993649D03*
X167983Y1025500D03*
Y1017500D03*
X148483Y1160500D03*
Y1178500D03*
X191483Y515500D03*
Y521000D03*
Y532000D03*
Y526500D03*
X172983Y663500D03*
Y659500D03*
Y651500D03*
X178983Y720000D03*
Y713000D03*
Y747000D03*
Y740000D03*
X189483Y1240500D03*
G54D15*
X8900Y139356D03*
Y142506D03*
X22500Y255425D03*
Y258575D03*
X10600Y862925D03*
Y866075D03*
X17500Y980925D03*
Y984075D03*
X53500Y801075D03*
Y797925D03*
X72500Y70575D03*
Y67425D03*
X59500Y104425D03*
Y107575D03*
Y89425D03*
Y92575D03*
X71500Y127575D03*
Y124425D03*
X56500Y292575D03*
Y289425D03*
X59500Y434925D03*
Y438075D03*
Y448925D03*
Y452075D03*
X72000Y769925D03*
Y773075D03*
X57500Y801075D03*
Y797925D03*
X75500Y846425D03*
Y849575D03*
X63500Y1019575D03*
Y1016425D03*
X87500Y132925D03*
Y136075D03*
X109000Y487425D03*
Y490575D03*
X144500Y71425D03*
Y74575D03*
Y85425D03*
Y88575D03*
X139000Y253925D03*
Y257075D03*
X145000Y432925D03*
X144500Y423075D03*
Y419925D03*
X145000Y436075D03*
Y779425D03*
Y782575D03*
X127000Y801425D03*
Y804575D03*
X142000Y984425D03*
Y987575D03*
X133000Y1128925D03*
Y1132075D03*
X167000Y291575D03*
Y288425D03*
X149000Y779425D03*
Y782575D03*
X179000Y387425D03*
Y390575D03*
X181500Y490075D03*
Y486925D03*
X177500D03*
Y490075D03*
X179000Y857575D03*
Y854425D03*
X172000Y1020575D03*
Y1017425D03*
X194854Y141356D03*
Y144506D03*
X197500Y869425D03*
Y872575D03*
G54D42*
X35260Y643441D03*
Y646000D03*
Y648559D03*
X42740D03*
Y646000D03*
Y643441D03*
X35260Y654441D03*
Y657000D03*
Y659559D03*
X42740D03*
Y657000D03*
Y654441D03*
X35260Y666941D03*
Y669500D03*
Y672059D03*
X42740D03*
Y669500D03*
Y666941D03*
X35260Y679441D03*
Y682000D03*
Y684559D03*
X42740D03*
Y682000D03*
Y679441D03*
G54D51*
X95500Y388000D03*
X158000Y17500D03*
X166960Y1304230D03*
G54D33*
X42717Y595122D03*
X101772Y178779D03*
Y926810D03*
X160827Y595122D03*
G54D61*
G01X-320500Y-470483D02*
Y2626000D01*
X2967000D01*
Y-470483D01*
X-320500D01*
G01X329322Y-314459D02*
Y-319459D01*
G01X327865Y-314459D02*
X330779D01*
G01X335689Y-319459D02*
X333155D01*
Y-314459D01*
X335689D01*
G01X334675Y-316876D02*
X333155D01*
G01X338255Y-314459D02*
Y-319459D01*
X340789D01*
G01X344622Y-319626D02*
X344495Y-319542D01*
Y-319376D01*
X344622Y-319292D01*
X344749Y-319376D01*
Y-319542D01*
X344622Y-319626D01*
G01Y-317376D02*
X344495Y-317292D01*
Y-317126D01*
X344622Y-317042D01*
X344749Y-317126D01*
Y-317292D01*
X344622Y-317376D01*
G01X349405Y-321126D02*
X348772Y-320292D01*
X348455Y-319459D01*
Y-316126D01*
X348772Y-315292D01*
X349405Y-314459D01*
G01X354822D02*
X354315Y-314626D01*
X353935Y-315042D01*
X353682Y-315542D01*
X353492Y-316209D01*
X353429Y-316959D01*
X353492Y-317709D01*
X353682Y-318376D01*
X353935Y-318876D01*
X354315Y-319292D01*
X354822Y-319459D01*
X355329Y-319292D01*
X355709Y-318876D01*
X355962Y-318376D01*
X356152Y-317709D01*
X356215Y-316959D01*
X356152Y-316209D01*
X355962Y-315542D01*
X355709Y-315042D01*
X355329Y-314626D01*
X354822Y-314459D01*
G01X358529Y-318459D02*
X358909Y-319042D01*
X359415Y-319376D01*
X359985Y-319459D01*
X360492Y-319376D01*
X360999Y-318959D01*
X361315Y-318459D01*
X361379Y-317959D01*
X361252Y-317376D01*
X360809Y-316959D01*
X360365Y-316792D01*
X359795D01*
G01X360365D02*
X360745Y-316542D01*
X361062Y-316126D01*
X361189Y-315626D01*
X361062Y-315126D01*
X360745Y-314709D01*
X360175Y-314459D01*
X359605Y-314542D01*
X359035Y-314876D01*
G01X365339Y-321126D02*
X365972Y-320292D01*
X366289Y-319459D01*
Y-316126D01*
X365972Y-315292D01*
X365339Y-314459D01*
G01X368729Y-318459D02*
X369109Y-319042D01*
X369615Y-319376D01*
X370185Y-319459D01*
X370692Y-319376D01*
X371199Y-318959D01*
X371515Y-318459D01*
X371579Y-317959D01*
X371452Y-317376D01*
X371009Y-316959D01*
X370565Y-316792D01*
X369995D01*
G01X370565D02*
X370945Y-316542D01*
X371262Y-316126D01*
X371389Y-315626D01*
X371262Y-315126D01*
X370945Y-314709D01*
X370375Y-314459D01*
X369805Y-314542D01*
X369235Y-314876D01*
G01X374019Y-315292D02*
X374399Y-314792D01*
X374842Y-314542D01*
X375349Y-314459D01*
X375982Y-314626D01*
X376425Y-315042D01*
X376552Y-315542D01*
X376489Y-316042D01*
X376235Y-316459D01*
X374969Y-317292D01*
X374399Y-317876D01*
X374019Y-318709D01*
X373892Y-319459D01*
X376552D01*
G01X380195D02*
X380322Y-318376D01*
X380512Y-317459D01*
X380765Y-316626D01*
X381082Y-315709D01*
X381589Y-314459D01*
X379055D01*
G01X384599Y-317792D02*
X386245D01*
G01X389319Y-315292D02*
X389699Y-314792D01*
X390142Y-314542D01*
X390649Y-314459D01*
X391282Y-314626D01*
X391725Y-315042D01*
X391852Y-315542D01*
X391789Y-316042D01*
X391535Y-316459D01*
X390269Y-317292D01*
X389699Y-317876D01*
X389319Y-318709D01*
X389192Y-319459D01*
X391852D01*
G01X394229Y-318459D02*
X394609Y-319042D01*
X395115Y-319376D01*
X395685Y-319459D01*
X396192Y-319376D01*
X396699Y-318959D01*
X397015Y-318459D01*
X397079Y-317959D01*
X396952Y-317376D01*
X396509Y-316959D01*
X396065Y-316792D01*
X395495D01*
G01X396065D02*
X396445Y-316542D01*
X396762Y-316126D01*
X396889Y-315626D01*
X396762Y-315126D01*
X396445Y-314709D01*
X395875Y-314459D01*
X395305Y-314542D01*
X394735Y-314876D01*
G01X401482Y-319459D02*
Y-314459D01*
X399139Y-318042D01*
X402305D01*
G01X404429Y-318709D02*
X404809Y-319126D01*
X405252Y-319376D01*
X405822Y-319459D01*
X406392Y-319292D01*
X406835Y-318959D01*
X407152Y-318376D01*
X407215Y-317709D01*
X407089Y-317042D01*
X406772Y-316626D01*
X406329Y-316292D01*
X405885Y-316209D01*
X405442Y-316292D01*
X404872Y-316626D01*
X405062Y-314459D01*
X406772D01*
G01X414819Y-319459D02*
Y-314459D01*
X417225D01*
G01X416339Y-316876D02*
X414819D01*
G01X419539Y-319459D02*
X421122Y-314459D01*
X422705Y-319459D01*
G01X422135Y-317709D02*
X420109D01*
G01X424892Y-319459D02*
X427552Y-314459D01*
G01X424892D02*
X427552Y-319459D01*
G01X431322Y-319626D02*
X431195Y-319542D01*
Y-319376D01*
X431322Y-319292D01*
X431449Y-319376D01*
Y-319542D01*
X431322Y-319626D01*
G01Y-317376D02*
X431195Y-317292D01*
Y-317126D01*
X431322Y-317042D01*
X431449Y-317126D01*
Y-317292D01*
X431322Y-317376D01*
G01X436105Y-321126D02*
X435472Y-320292D01*
X435155Y-319459D01*
Y-316126D01*
X435472Y-315292D01*
X436105Y-314459D01*
G01X441522D02*
X441015Y-314626D01*
X440635Y-315042D01*
X440382Y-315542D01*
X440192Y-316209D01*
X440129Y-316959D01*
X440192Y-317709D01*
X440382Y-318376D01*
X440635Y-318876D01*
X441015Y-319292D01*
X441522Y-319459D01*
X442029Y-319292D01*
X442409Y-318876D01*
X442662Y-318376D01*
X442852Y-317709D01*
X442915Y-316959D01*
X442852Y-316209D01*
X442662Y-315542D01*
X442409Y-315042D01*
X442029Y-314626D01*
X441522Y-314459D01*
G01X445229Y-318459D02*
X445609Y-319042D01*
X446115Y-319376D01*
X446685Y-319459D01*
X447192Y-319376D01*
X447699Y-318959D01*
X448015Y-318459D01*
X448079Y-317959D01*
X447952Y-317376D01*
X447509Y-316959D01*
X447065Y-316792D01*
X446495D01*
G01X447065D02*
X447445Y-316542D01*
X447762Y-316126D01*
X447889Y-315626D01*
X447762Y-315126D01*
X447445Y-314709D01*
X446875Y-314459D01*
X446305Y-314542D01*
X445735Y-314876D01*
G01X452039Y-321126D02*
X452672Y-320292D01*
X452989Y-319459D01*
Y-316126D01*
X452672Y-315292D01*
X452039Y-314459D01*
G01X455429Y-318459D02*
X455809Y-319042D01*
X456315Y-319376D01*
X456885Y-319459D01*
X457392Y-319376D01*
X457899Y-318959D01*
X458215Y-318459D01*
X458279Y-317959D01*
X458152Y-317376D01*
X457709Y-316959D01*
X457265Y-316792D01*
X456695D01*
G01X457265D02*
X457645Y-316542D01*
X457962Y-316126D01*
X458089Y-315626D01*
X457962Y-315126D01*
X457645Y-314709D01*
X457075Y-314459D01*
X456505Y-314542D01*
X455935Y-314876D01*
G01X460845Y-318876D02*
X461289Y-319292D01*
X461795Y-319459D01*
X462302Y-319292D01*
X462745Y-318792D01*
X463062Y-318042D01*
X463189Y-317292D01*
Y-316376D01*
X463062Y-315626D01*
X462745Y-314959D01*
X462365Y-314626D01*
X461922Y-314459D01*
X461415Y-314626D01*
X461035Y-314959D01*
X460782Y-315459D01*
X460655Y-316126D01*
X460782Y-316709D01*
X461099Y-317292D01*
X461479Y-317626D01*
X461922Y-317709D01*
X462429Y-317542D01*
X462809Y-317126D01*
X463189Y-316376D01*
G01X466895Y-319459D02*
X467022Y-318376D01*
X467212Y-317459D01*
X467465Y-316626D01*
X467782Y-315709D01*
X468289Y-314459D01*
X465755D01*
G01X471299Y-317792D02*
X472945D01*
G01X475829Y-318459D02*
X476209Y-319042D01*
X476715Y-319376D01*
X477285Y-319459D01*
X477792Y-319376D01*
X478299Y-318959D01*
X478615Y-318459D01*
X478679Y-317959D01*
X478552Y-317376D01*
X478109Y-316959D01*
X477665Y-316792D01*
X477095D01*
G01X477665D02*
X478045Y-316542D01*
X478362Y-316126D01*
X478489Y-315626D01*
X478362Y-315126D01*
X478045Y-314709D01*
X477475Y-314459D01*
X476905Y-314542D01*
X476335Y-314876D01*
G01X481119Y-317376D02*
X481562Y-316792D01*
X481942Y-316459D01*
X482449Y-316292D01*
X482892Y-316459D01*
X483209Y-316792D01*
X483462Y-317292D01*
X483525Y-317876D01*
X483462Y-318376D01*
X483209Y-318876D01*
X482829Y-319292D01*
X482385Y-319459D01*
X481879Y-319292D01*
X481435Y-318792D01*
X481182Y-318042D01*
X481119Y-317209D01*
X481245Y-316126D01*
X481435Y-315542D01*
X481752Y-314959D01*
X482195Y-314542D01*
X482639Y-314459D01*
X483082Y-314626D01*
X483399Y-315042D01*
G01X487422Y-319459D02*
Y-314459D01*
X486662Y-315459D01*
G01Y-319459D02*
X488182D01*
G01X493282D02*
Y-314459D01*
X490939Y-318042D01*
X494105D01*
G01X317322Y-249459D02*
Y-324459D01*
X817322D01*
Y-249459D01*
X317322D01*
G01X512322D02*
Y-324459D01*
G01Y-299459D02*
X615322D01*
Y-274459D01*
G01X512322D02*
X615322D01*
G01X622829Y-309459D02*
Y-304459D01*
X624095D01*
X624602Y-304709D01*
X624982Y-305042D01*
X625299Y-305542D01*
X625552Y-306126D01*
X625615Y-306959D01*
X625552Y-307792D01*
X625299Y-308376D01*
X624982Y-308876D01*
X624602Y-309209D01*
X624095Y-309459D01*
X622829D01*
G01X627739D02*
X629322Y-304459D01*
X630905Y-309459D01*
G01X630335Y-307709D02*
X628309D01*
G01X634422Y-304459D02*
Y-309459D01*
G01X632965Y-304459D02*
X635879D01*
G01X640789Y-309459D02*
X638255D01*
Y-304459D01*
X640789D01*
G01X639775Y-306876D02*
X638255D01*
G01X644622Y-309626D02*
X644495Y-309542D01*
Y-309376D01*
X644622Y-309292D01*
X644749Y-309376D01*
Y-309542D01*
X644622Y-309626D01*
G01Y-307376D02*
X644495Y-307292D01*
Y-307126D01*
X644622Y-307042D01*
X644749Y-307126D01*
Y-307292D01*
X644622Y-307376D01*
G01X617322Y-249459D02*
Y-324459D01*
G01X615322Y-249459D02*
Y-324459D01*
G01X622955Y-284459D02*
Y-279459D01*
X624475D01*
X624982Y-279709D01*
X625362Y-280292D01*
X625489Y-280959D01*
X625362Y-281626D01*
X625045Y-282126D01*
X624475Y-282376D01*
X622955D01*
G01X628182Y-284626D02*
X630462Y-279459D01*
G01X632965Y-284459D02*
Y-279459D01*
X635879Y-284459D01*
Y-279459D01*
G01X639522Y-284626D02*
X639395Y-284542D01*
Y-284376D01*
X639522Y-284292D01*
X639649Y-284376D01*
Y-284542D01*
X639522Y-284626D01*
G01Y-282376D02*
X639395Y-282292D01*
Y-282126D01*
X639522Y-282042D01*
X639649Y-282126D01*
Y-282292D01*
X639522Y-282376D01*
G01X617322Y-299459D02*
X817322D01*
G01X622955Y-259459D02*
Y-254459D01*
X624475D01*
X624982Y-254709D01*
X625362Y-255292D01*
X625489Y-255959D01*
X625362Y-256626D01*
X625045Y-257126D01*
X624475Y-257376D01*
X622955D01*
G01X628055Y-259459D02*
Y-254459D01*
X629639D01*
X630145Y-254709D01*
X630462Y-255042D01*
X630589Y-255709D01*
X630462Y-256376D01*
X630082Y-256792D01*
X629639Y-257042D01*
X628055D01*
G01X629639D02*
X630589Y-259459D01*
G01X634422D02*
X633915Y-259376D01*
X633472Y-259042D01*
X633092Y-258542D01*
X632839Y-257959D01*
X632712Y-257292D01*
Y-256626D01*
X632839Y-255959D01*
X633092Y-255376D01*
X633472Y-254876D01*
X633915Y-254542D01*
X634422Y-254459D01*
X634929Y-254542D01*
X635372Y-254876D01*
X635752Y-255376D01*
X636005Y-255959D01*
X636132Y-256626D01*
Y-257292D01*
X636005Y-257959D01*
X635752Y-258542D01*
X635372Y-259042D01*
X634929Y-259376D01*
X634422Y-259459D01*
G01X638255Y-258459D02*
X638572Y-258959D01*
X638952Y-259292D01*
X639395Y-259459D01*
X639902Y-259292D01*
X640282Y-258959D01*
X640662Y-258459D01*
X640789Y-257792D01*
Y-254459D01*
G01X645889Y-259459D02*
X643355D01*
Y-254459D01*
X645889D01*
G01X644875Y-256876D02*
X643355D01*
G01X651115Y-254876D02*
X650735Y-254626D01*
X650292Y-254459D01*
X649785D01*
X649215Y-254709D01*
X648772Y-255126D01*
X648455Y-255626D01*
X648202Y-256459D01*
X648139Y-257209D01*
X648265Y-257959D01*
X648455Y-258459D01*
X648835Y-258959D01*
X649279Y-259292D01*
X649722Y-259459D01*
X650165D01*
X650609Y-259292D01*
X650989Y-259042D01*
X651305Y-258709D01*
G01X654822Y-254459D02*
Y-259459D01*
G01X653365Y-254459D02*
X656279D01*
G01X659922Y-259626D02*
X659795Y-259542D01*
Y-259376D01*
X659922Y-259292D01*
X660049Y-259376D01*
Y-259542D01*
X659922Y-259626D01*
G01Y-257376D02*
X659795Y-257292D01*
Y-257126D01*
X659922Y-257042D01*
X660049Y-257126D01*
Y-257292D01*
X659922Y-257376D01*
G01X617322Y-274459D02*
X817322D01*
G01X734955Y-301959D02*
Y-306959D01*
X737489D01*
G01X740562Y-301959D02*
X742082D01*
G01X741322D02*
Y-306959D01*
G01X740562D02*
X742082D01*
G01X746929Y-304292D02*
X747182Y-304042D01*
X747372Y-303626D01*
X747499Y-303042D01*
X747372Y-302542D01*
X747119Y-302209D01*
X746675Y-301959D01*
X744965D01*
Y-306959D01*
X747055D01*
X747499Y-306626D01*
X747752Y-306126D01*
X747879Y-305542D01*
X747752Y-304959D01*
X747372Y-304459D01*
X746929Y-304292D01*
X744965D01*
G01X751522Y-307126D02*
X751395Y-307042D01*
Y-306876D01*
X751522Y-306792D01*
X751649Y-306876D01*
Y-307042D01*
X751522Y-307126D01*
G01Y-304876D02*
X751395Y-304792D01*
Y-304626D01*
X751522Y-304542D01*
X751649Y-304626D01*
Y-304792D01*
X751522Y-304876D01*
G01X732322Y-299459D02*
Y-324459D01*
G01X779222Y-301959D02*
Y-306959D01*
G01X777765Y-301959D02*
X780679D01*
G01X784322Y-306959D02*
X783942Y-306876D01*
X783562Y-306542D01*
X783309Y-305959D01*
X783182Y-305292D01*
X783309Y-304626D01*
X783562Y-304042D01*
X783942Y-303709D01*
X784322Y-303626D01*
X784702Y-303709D01*
X785082Y-304042D01*
X785335Y-304626D01*
X785399Y-305292D01*
X785335Y-305959D01*
X785082Y-306542D01*
X784702Y-306876D01*
X784322Y-306959D01*
G01X789422D02*
X789042Y-306876D01*
X788662Y-306542D01*
X788409Y-305959D01*
X788282Y-305292D01*
X788409Y-304626D01*
X788662Y-304042D01*
X789042Y-303709D01*
X789422Y-303626D01*
X789802Y-303709D01*
X790182Y-304042D01*
X790435Y-304626D01*
X790499Y-305292D01*
X790435Y-305959D01*
X790182Y-306542D01*
X789802Y-306876D01*
X789422Y-306959D01*
G01X794522D02*
Y-301959D01*
G01X799622Y-307126D02*
X799495Y-307042D01*
Y-306876D01*
X799622Y-306792D01*
X799749Y-306876D01*
Y-307042D01*
X799622Y-307126D01*
G01Y-304876D02*
X799495Y-304792D01*
Y-304626D01*
X799622Y-304542D01*
X799749Y-304626D01*
Y-304792D01*
X799622Y-304876D01*
G01X775322Y-299459D02*
Y-324459D01*
G01Y-274459D02*
Y-299459D01*
G01X777955Y-281959D02*
Y-276959D01*
X779539D01*
X780045Y-277209D01*
X780362Y-277542D01*
X780489Y-278209D01*
X780362Y-278876D01*
X779982Y-279292D01*
X779539Y-279542D01*
X777955D01*
G01X779539D02*
X780489Y-281959D01*
G01X785589D02*
X783055D01*
Y-276959D01*
X785589D01*
G01X784575Y-279376D02*
X783055D01*
G01X787839Y-276959D02*
X789422Y-281959D01*
X791005Y-276959D01*
G01X794522Y-282126D02*
X794395Y-282042D01*
Y-281876D01*
X794522Y-281792D01*
X794649Y-281876D01*
Y-282042D01*
X794522Y-282126D01*
G01Y-279876D02*
X794395Y-279792D01*
Y-279626D01*
X794522Y-279542D01*
X794649Y-279626D01*
Y-279792D01*
X794522Y-279876D01*
G01X798082Y-326159D02*
X798162Y-326084D01*
X798222Y-325959D01*
X798262Y-325784D01*
X798222Y-325634D01*
X798142Y-325534D01*
X798002Y-325459D01*
X797462D01*
Y-326959D01*
X798122D01*
X798262Y-326859D01*
X798342Y-326709D01*
X798382Y-326534D01*
X798342Y-326359D01*
X798222Y-326209D01*
X798082Y-326159D01*
X797462D01*
G01X799482Y-326959D02*
Y-325959D01*
G01Y-326134D02*
X799402Y-326034D01*
X799282Y-325984D01*
X799142Y-325959D01*
X799002Y-326009D01*
X798882Y-326109D01*
X798802Y-326259D01*
X798762Y-326459D01*
X798802Y-326659D01*
X798882Y-326809D01*
X799002Y-326909D01*
X799142Y-326959D01*
X799282Y-326934D01*
X799402Y-326859D01*
X799482Y-326759D01*
G01X800022Y-326784D02*
X800122Y-326884D01*
X800262Y-326959D01*
X800382D01*
X800502Y-326909D01*
X800582Y-326834D01*
X800622Y-326734D01*
X800602Y-326584D01*
X800522Y-326509D01*
X800162Y-326359D01*
X800082Y-326184D01*
X800122Y-326059D01*
X800202Y-325984D01*
X800322Y-325959D01*
X800442Y-325984D01*
X800562Y-326059D01*
G01X801222Y-326284D02*
X801862D01*
X801802Y-326109D01*
X801702Y-326009D01*
X801562Y-325959D01*
X801422Y-325984D01*
X801302Y-326059D01*
X801222Y-326234D01*
X801182Y-326384D01*
Y-326534D01*
X801222Y-326684D01*
X801322Y-326834D01*
X801442Y-326934D01*
X801582Y-326959D01*
X801722Y-326909D01*
X801862Y-326759D01*
G01X802362Y-326959D02*
Y-325459D01*
G01Y-326209D02*
X802462Y-326059D01*
X802582Y-325984D01*
X802702Y-325959D01*
X802882Y-326009D01*
X803002Y-326109D01*
X803082Y-326284D01*
Y-326484D01*
X803042Y-326684D01*
X802962Y-326834D01*
X802822Y-326934D01*
X802702Y-326959D01*
X802582Y-326934D01*
X802462Y-326859D01*
X802362Y-326734D01*
G01X803922Y-326959D02*
X803802Y-326934D01*
X803682Y-326834D01*
X803602Y-326659D01*
X803562Y-326459D01*
X803602Y-326259D01*
X803682Y-326084D01*
X803802Y-325984D01*
X803922Y-325959D01*
X804042Y-325984D01*
X804162Y-326084D01*
X804242Y-326259D01*
X804262Y-326459D01*
X804242Y-326659D01*
X804162Y-326834D01*
X804042Y-326934D01*
X803922Y-326959D01*
G01X805482D02*
Y-325959D01*
G01Y-326134D02*
X805402Y-326034D01*
X805282Y-325984D01*
X805142Y-325959D01*
X805002Y-326009D01*
X804882Y-326109D01*
X804802Y-326259D01*
X804762Y-326459D01*
X804802Y-326659D01*
X804882Y-326809D01*
X805002Y-326909D01*
X805142Y-326959D01*
X805282Y-326934D01*
X805402Y-326859D01*
X805482Y-326759D01*
G01X806042Y-326959D02*
Y-325959D01*
G01Y-326159D02*
X806142Y-326059D01*
X806242Y-325984D01*
X806382Y-325959D01*
X806482Y-325984D01*
X806602Y-326059D01*
G01X807882Y-325459D02*
Y-326959D01*
G01Y-326734D02*
X807802Y-326859D01*
X807682Y-326934D01*
X807542Y-326959D01*
X807382Y-326909D01*
X807262Y-326784D01*
X807182Y-326634D01*
X807162Y-326459D01*
X807182Y-326284D01*
X807262Y-326134D01*
X807382Y-326009D01*
X807542Y-325959D01*
X807682Y-325984D01*
X807782Y-326034D01*
X807882Y-326134D01*
G01X809522Y-326959D02*
Y-325459D01*
X810022D01*
X810182Y-325534D01*
X810282Y-325634D01*
X810322Y-325834D01*
X810282Y-326034D01*
X810162Y-326159D01*
X810022Y-326234D01*
X809522D01*
G01X810022D02*
X810322Y-326959D01*
G01X810822Y-326284D02*
X811462D01*
X811402Y-326109D01*
X811302Y-326009D01*
X811162Y-325959D01*
X811022Y-325984D01*
X810902Y-326059D01*
X810822Y-326234D01*
X810782Y-326384D01*
Y-326534D01*
X810822Y-326684D01*
X810922Y-326834D01*
X811042Y-326934D01*
X811182Y-326959D01*
X811322Y-326909D01*
X811462Y-326759D01*
G01X811962Y-325959D02*
X812322Y-326959D01*
X812682Y-325959D01*
G01X813522Y-327009D02*
X813482Y-326984D01*
Y-326934D01*
X813522Y-326909D01*
X813562Y-326934D01*
Y-326984D01*
X813522Y-327009D01*
G01X814682Y-326959D02*
X814722Y-326634D01*
X814782Y-326359D01*
X814862Y-326109D01*
X814962Y-325834D01*
X815122Y-325459D01*
X814322D01*
G01X816082Y-326159D02*
X816162Y-326084D01*
X816222Y-325959D01*
X816262Y-325784D01*
X816222Y-325634D01*
X816142Y-325534D01*
X816002Y-325459D01*
X815462D01*
Y-326959D01*
X816122D01*
X816262Y-326859D01*
X816342Y-326709D01*
X816382Y-326534D01*
X816342Y-326359D01*
X816222Y-326209D01*
X816082Y-326159D01*
X815462D01*
G01X-320500Y-470483D02*
Y2626000D01*
X2967000D01*
Y-470483D01*
X-320500D01*
G01X331395Y-304184D02*
X330925Y-303869D01*
X330377Y-303659D01*
X329750D01*
X329045Y-303974D01*
X328497Y-304499D01*
X328105Y-305129D01*
X327792Y-306179D01*
X327714Y-307124D01*
X327870Y-308069D01*
X328105Y-308699D01*
X328575Y-309329D01*
X329124Y-309749D01*
X329672Y-309959D01*
X330220D01*
X330769Y-309749D01*
X331239Y-309434D01*
X331630Y-309014D01*
G01X335032Y-303659D02*
X336912D01*
G01X335972D02*
Y-309959D01*
G01X335032D02*
X336912D01*
G01X342272Y-303659D02*
Y-309959D01*
G01X340470Y-303659D02*
X344074D01*
G01X348572Y-309959D02*
Y-307124D01*
X347005Y-303659D01*
G01X350139D02*
X348572Y-307124D01*
G01X359449Y-308699D02*
X359919Y-309434D01*
X360545Y-309854D01*
X361250Y-309959D01*
X361877Y-309854D01*
X362504Y-309329D01*
X362895Y-308699D01*
X362974Y-308069D01*
X362817Y-307334D01*
X362269Y-306809D01*
X361720Y-306599D01*
X361015D01*
G01X361720D02*
X362190Y-306284D01*
X362582Y-305759D01*
X362739Y-305129D01*
X362582Y-304499D01*
X362190Y-303974D01*
X361485Y-303659D01*
X360780Y-303764D01*
X360075Y-304184D01*
G01X365749Y-308699D02*
X366219Y-309434D01*
X366845Y-309854D01*
X367550Y-309959D01*
X368177Y-309854D01*
X368804Y-309329D01*
X369195Y-308699D01*
X369274Y-308069D01*
X369117Y-307334D01*
X368569Y-306809D01*
X368020Y-306599D01*
X367315D01*
G01X368020D02*
X368490Y-306284D01*
X368882Y-305759D01*
X369039Y-305129D01*
X368882Y-304499D01*
X368490Y-303974D01*
X367785Y-303659D01*
X367080Y-303764D01*
X366375Y-304184D01*
G01X372049Y-308699D02*
X372519Y-309434D01*
X373145Y-309854D01*
X373850Y-309959D01*
X374477Y-309854D01*
X375104Y-309329D01*
X375495Y-308699D01*
X375574Y-308069D01*
X375417Y-307334D01*
X374869Y-306809D01*
X374320Y-306599D01*
X373615D01*
G01X374320D02*
X374790Y-306284D01*
X375182Y-305759D01*
X375339Y-305129D01*
X375182Y-304499D01*
X374790Y-303974D01*
X374085Y-303659D01*
X373380Y-303764D01*
X372675Y-304184D01*
G01X379915Y-309959D02*
X380072Y-308594D01*
X380307Y-307439D01*
X380620Y-306389D01*
X381012Y-305234D01*
X381639Y-303659D01*
X378505D01*
G01X386215Y-309959D02*
X386372Y-308594D01*
X386607Y-307439D01*
X386920Y-306389D01*
X387312Y-305234D01*
X387939Y-303659D01*
X384805D01*
G01X392515Y-311114D02*
X392829Y-309749D01*
G01X398972Y-303659D02*
Y-309959D01*
G01X397170Y-303659D02*
X400774D01*
G01X403314Y-309959D02*
X405272Y-303659D01*
X407230Y-309959D01*
G01X406525Y-307754D02*
X404019D01*
G01X410632Y-303659D02*
X412512D01*
G01X411572D02*
Y-309959D01*
G01X410632D02*
X412512D01*
G01X415522Y-303659D02*
X416619Y-309959D01*
X417872Y-303659D01*
X419125Y-309959D01*
X420222Y-303659D01*
G01X422214Y-309959D02*
X424172Y-303659D01*
X426130Y-309959D01*
G01X425425Y-307754D02*
X422919D01*
G01X428670Y-309959D02*
Y-303659D01*
X432274Y-309959D01*
Y-303659D01*
G01X442680Y-312059D02*
X441897Y-311009D01*
X441505Y-309959D01*
Y-305759D01*
X441897Y-304709D01*
X442680Y-303659D01*
G01X454105Y-309959D02*
Y-303659D01*
X456064D01*
X456690Y-303974D01*
X457082Y-304394D01*
X457239Y-305234D01*
X457082Y-306074D01*
X456612Y-306599D01*
X456064Y-306914D01*
X454105D01*
G01X456064D02*
X457239Y-309959D01*
G01X461972Y-310169D02*
X461815Y-310064D01*
Y-309854D01*
X461972Y-309749D01*
X462129Y-309854D01*
Y-310064D01*
X461972Y-310169D01*
G01X468272Y-309959D02*
X467645Y-309854D01*
X467097Y-309434D01*
X466627Y-308804D01*
X466314Y-308069D01*
X466157Y-307229D01*
Y-306389D01*
X466314Y-305549D01*
X466627Y-304814D01*
X467097Y-304184D01*
X467645Y-303764D01*
X468272Y-303659D01*
X468899Y-303764D01*
X469447Y-304184D01*
X469917Y-304814D01*
X470230Y-305549D01*
X470387Y-306389D01*
Y-307229D01*
X470230Y-308069D01*
X469917Y-308804D01*
X469447Y-309434D01*
X468899Y-309854D01*
X468272Y-309959D01*
G01X474572Y-310169D02*
X474415Y-310064D01*
Y-309854D01*
X474572Y-309749D01*
X474729Y-309854D01*
Y-310064D01*
X474572Y-310169D01*
G01X482595Y-304184D02*
X482125Y-303869D01*
X481577Y-303659D01*
X480950D01*
X480245Y-303974D01*
X479697Y-304499D01*
X479305Y-305129D01*
X478992Y-306179D01*
X478914Y-307124D01*
X479070Y-308069D01*
X479305Y-308699D01*
X479775Y-309329D01*
X480324Y-309749D01*
X480872Y-309959D01*
X481420D01*
X481969Y-309749D01*
X482439Y-309434D01*
X482830Y-309014D01*
G01X487172Y-310169D02*
X487015Y-310064D01*
Y-309854D01*
X487172Y-309749D01*
X487329Y-309854D01*
Y-310064D01*
X487172Y-310169D01*
G01X493864Y-312059D02*
X494647Y-311009D01*
X495039Y-309959D01*
Y-305759D01*
X494647Y-304709D01*
X493864Y-303659D01*
G01X330142Y-296809D02*
X331709D01*
Y-298699D01*
X331239Y-299329D01*
X330690Y-299749D01*
X329907Y-299959D01*
X329124Y-299749D01*
X328575Y-299329D01*
X328105Y-298699D01*
X327792Y-297964D01*
X327635Y-297124D01*
Y-296389D01*
X327792Y-295759D01*
X328105Y-295024D01*
X328575Y-294394D01*
X329045Y-293974D01*
X329672Y-293659D01*
X330220D01*
X330847Y-293869D01*
X331317Y-294289D01*
G01X334249Y-293659D02*
Y-298174D01*
X334562Y-299119D01*
X335189Y-299749D01*
X335972Y-299959D01*
X336755Y-299749D01*
X337382Y-299119D01*
X337695Y-298174D01*
Y-293659D01*
G01X341332D02*
X343212D01*
G01X342272D02*
Y-299959D01*
G01X341332D02*
X343212D01*
G01X346927Y-299119D02*
X347554Y-299644D01*
X348259Y-299959D01*
X348885D01*
X349512Y-299644D01*
X349982Y-299119D01*
X350217Y-298384D01*
X350060Y-297649D01*
X349669Y-297019D01*
X348964Y-296599D01*
X348024Y-296389D01*
X347475Y-295969D01*
X347240Y-295234D01*
X347397Y-294499D01*
X347789Y-293974D01*
X348337Y-293659D01*
X348885D01*
X349434Y-293869D01*
X349904Y-294394D01*
G01X353227Y-299959D02*
Y-293659D01*
G01X356517D02*
Y-299959D01*
G01Y-296809D02*
X353227D01*
G01X359214Y-299959D02*
X361172Y-293659D01*
X363130Y-299959D01*
G01X362425Y-297754D02*
X359919D01*
G01X365670Y-299959D02*
Y-293659D01*
X369274Y-299959D01*
Y-293659D01*
G01X378349Y-299959D02*
Y-293659D01*
X379915D01*
X380542Y-293974D01*
X381012Y-294394D01*
X381404Y-295024D01*
X381717Y-295759D01*
X381795Y-296809D01*
X381717Y-297859D01*
X381404Y-298594D01*
X381012Y-299224D01*
X380542Y-299644D01*
X379915Y-299959D01*
X378349D01*
G01X385432Y-293659D02*
X387312D01*
G01X386372D02*
Y-299959D01*
G01X385432D02*
X387312D01*
G01X391027Y-299119D02*
X391654Y-299644D01*
X392359Y-299959D01*
X392985D01*
X393612Y-299644D01*
X394082Y-299119D01*
X394317Y-298384D01*
X394160Y-297649D01*
X393769Y-297019D01*
X393064Y-296599D01*
X392124Y-296389D01*
X391575Y-295969D01*
X391340Y-295234D01*
X391497Y-294499D01*
X391889Y-293974D01*
X392437Y-293659D01*
X392985D01*
X393534Y-293869D01*
X394004Y-294394D01*
G01X398972Y-293659D02*
Y-299959D01*
G01X397170Y-293659D02*
X400774D01*
G01X405272Y-300169D02*
X405115Y-300064D01*
Y-299854D01*
X405272Y-299749D01*
X405429Y-299854D01*
Y-300064D01*
X405272Y-300169D01*
G01X411415Y-301114D02*
X411729Y-299749D01*
G01X417872Y-293659D02*
Y-299959D01*
G01X416070Y-293659D02*
X419674D01*
G01X422214Y-299959D02*
X424172Y-293659D01*
X426130Y-299959D01*
G01X425425Y-297754D02*
X422919D01*
G01X430472Y-299959D02*
X429845Y-299854D01*
X429297Y-299434D01*
X428827Y-298804D01*
X428514Y-298069D01*
X428357Y-297229D01*
Y-296389D01*
X428514Y-295549D01*
X428827Y-294814D01*
X429297Y-294184D01*
X429845Y-293764D01*
X430472Y-293659D01*
X431099Y-293764D01*
X431647Y-294184D01*
X432117Y-294814D01*
X432430Y-295549D01*
X432587Y-296389D01*
Y-297229D01*
X432430Y-298069D01*
X432117Y-298804D01*
X431647Y-299434D01*
X431099Y-299854D01*
X430472Y-299959D01*
G01X436772D02*
Y-297124D01*
X435205Y-293659D01*
G01X438339D02*
X436772Y-297124D01*
G01X441349Y-293659D02*
Y-298174D01*
X441662Y-299119D01*
X442289Y-299749D01*
X443072Y-299959D01*
X443855Y-299749D01*
X444482Y-299119D01*
X444795Y-298174D01*
Y-293659D01*
G01X447414Y-299959D02*
X449372Y-293659D01*
X451330Y-299959D01*
G01X450625Y-297754D02*
X448119D01*
G01X453870Y-299959D02*
Y-293659D01*
X457474Y-299959D01*
Y-293659D01*
G01X327870Y-289959D02*
Y-283659D01*
X331474Y-289959D01*
Y-283659D01*
G01X335972Y-289959D02*
X335345Y-289854D01*
X334797Y-289434D01*
X334327Y-288804D01*
X334014Y-288069D01*
X333857Y-287229D01*
Y-286389D01*
X334014Y-285549D01*
X334327Y-284814D01*
X334797Y-284184D01*
X335345Y-283764D01*
X335972Y-283659D01*
X336599Y-283764D01*
X337147Y-284184D01*
X337617Y-284814D01*
X337930Y-285549D01*
X338087Y-286389D01*
Y-287229D01*
X337930Y-288069D01*
X337617Y-288804D01*
X337147Y-289434D01*
X336599Y-289854D01*
X335972Y-289959D01*
G01X342272Y-290169D02*
X342115Y-290064D01*
Y-289854D01*
X342272Y-289749D01*
X342429Y-289854D01*
Y-290064D01*
X342272Y-290169D01*
G01X347084Y-284709D02*
X347554Y-284079D01*
X348102Y-283764D01*
X348729Y-283659D01*
X349512Y-283869D01*
X350060Y-284394D01*
X350217Y-285024D01*
X350139Y-285654D01*
X349825Y-286179D01*
X348259Y-287229D01*
X347554Y-287964D01*
X347084Y-289014D01*
X346927Y-289959D01*
X350217D01*
G01X354872D02*
Y-283659D01*
X353932Y-284919D01*
G01Y-289959D02*
X355812D01*
G01X361172D02*
Y-283659D01*
X360232Y-284919D01*
G01Y-289959D02*
X362112D01*
G01X367315Y-291114D02*
X367629Y-289749D01*
G01X371422Y-283659D02*
X372519Y-289959D01*
X373772Y-283659D01*
X375025Y-289959D01*
X376122Y-283659D01*
G01X381639Y-289959D02*
X378505D01*
Y-283659D01*
X381639D01*
G01X380385Y-286704D02*
X378505D01*
G01X384570Y-289959D02*
Y-283659D01*
X388174Y-289959D01*
Y-283659D01*
G01X391027Y-289959D02*
Y-283659D01*
G01X394317D02*
Y-289959D01*
G01Y-286809D02*
X391027D01*
G01X397249Y-283659D02*
Y-288174D01*
X397562Y-289119D01*
X398189Y-289749D01*
X398972Y-289959D01*
X399755Y-289749D01*
X400382Y-289119D01*
X400695Y-288174D01*
Y-283659D01*
G01X403314Y-289959D02*
X405272Y-283659D01*
X407230Y-289959D01*
G01X406525Y-287754D02*
X404019D01*
G01X416384Y-284709D02*
X416854Y-284079D01*
X417402Y-283764D01*
X418029Y-283659D01*
X418812Y-283869D01*
X419360Y-284394D01*
X419517Y-285024D01*
X419439Y-285654D01*
X419125Y-286179D01*
X417559Y-287229D01*
X416854Y-287964D01*
X416384Y-289014D01*
X416227Y-289959D01*
X419517D01*
G01X422370D02*
Y-283659D01*
X425974Y-289959D01*
Y-283659D01*
G01X428749Y-289959D02*
Y-283659D01*
X430315D01*
X430942Y-283974D01*
X431412Y-284394D01*
X431804Y-285024D01*
X432117Y-285759D01*
X432195Y-286809D01*
X432117Y-287859D01*
X431804Y-288594D01*
X431412Y-289224D01*
X430942Y-289644D01*
X430315Y-289959D01*
X428749D01*
G01X441505D02*
Y-283659D01*
X443464D01*
X444090Y-283974D01*
X444482Y-284394D01*
X444639Y-285234D01*
X444482Y-286074D01*
X444012Y-286599D01*
X443464Y-286914D01*
X441505D01*
G01X443464D02*
X444639Y-289959D01*
G01X447649D02*
Y-283659D01*
X449215D01*
X449842Y-283974D01*
X450312Y-284394D01*
X450704Y-285024D01*
X451017Y-285759D01*
X451095Y-286809D01*
X451017Y-287859D01*
X450704Y-288594D01*
X450312Y-289224D01*
X449842Y-289644D01*
X449215Y-289959D01*
X447649D01*
G01X455672Y-290169D02*
X455515Y-290064D01*
Y-289854D01*
X455672Y-289749D01*
X455829Y-289854D01*
Y-290064D01*
X455672Y-290169D01*
G01X351972Y-279259D02*
X349452Y-278842D01*
X347247Y-277176D01*
X345357Y-274676D01*
X344097Y-271759D01*
X343467Y-268426D01*
Y-265092D01*
X344097Y-261759D01*
X345357Y-258842D01*
X347247Y-256343D01*
X349452Y-254676D01*
X351972Y-254259D01*
X354492Y-254676D01*
X356697Y-256343D01*
X358587Y-258842D01*
X359847Y-261759D01*
X360477Y-265092D01*
Y-268426D01*
X359847Y-271759D01*
X358587Y-274676D01*
X356697Y-277176D01*
X354492Y-278842D01*
X351972Y-279259D01*
G01X354492Y-272592D02*
X358272Y-279259D01*
G01X371817Y-262593D02*
Y-274259D01*
X373077Y-277176D01*
X374967Y-278842D01*
X377172Y-279259D01*
X379377Y-278842D01*
X381267Y-277176D01*
X382527Y-274259D01*
G01Y-279259D02*
Y-262593D01*
G01X408042Y-279259D02*
Y-262593D01*
G01Y-265509D02*
X406782Y-263843D01*
X404892Y-263009D01*
X402687Y-262593D01*
X400482Y-263426D01*
X398592Y-265092D01*
X397332Y-267593D01*
X396702Y-270926D01*
X397332Y-274259D01*
X398592Y-276760D01*
X400482Y-278426D01*
X402687Y-279259D01*
X404892Y-278842D01*
X406782Y-277593D01*
X408042Y-275926D01*
G01X422217Y-279259D02*
Y-262593D01*
G01Y-266759D02*
X423477Y-264676D01*
X425367Y-263009D01*
X427887Y-262593D01*
X430092Y-263009D01*
X431982Y-264676D01*
X432927Y-267593D01*
Y-279259D01*
G01X452772Y-254259D02*
Y-279259D01*
G01X448362Y-262593D02*
X457182D01*
G01X483642Y-279259D02*
Y-262593D01*
G01Y-265509D02*
X482382Y-263843D01*
X480492Y-263009D01*
X478287Y-262593D01*
X476082Y-263426D01*
X474192Y-265092D01*
X472932Y-267593D01*
X472302Y-270926D01*
X472932Y-274259D01*
X474192Y-276760D01*
X476082Y-278426D01*
X478287Y-279259D01*
X480492Y-278842D01*
X482382Y-277593D01*
X483642Y-275926D01*
G01X523322Y-258959D02*
Y-266959D01*
X527322D01*
G01X535122D02*
Y-261626D01*
G01Y-262559D02*
X534722Y-262026D01*
X534122Y-261759D01*
X533422Y-261626D01*
X532722Y-261892D01*
X532122Y-262426D01*
X531722Y-263226D01*
X531522Y-264292D01*
X531722Y-265359D01*
X532122Y-266159D01*
X532722Y-266692D01*
X533422Y-266959D01*
X534122Y-266826D01*
X534722Y-266426D01*
X535122Y-265893D01*
G01X539222Y-269359D02*
X539822Y-269626D01*
X540622Y-269359D01*
X541122Y-268826D01*
X541522Y-268159D01*
X542122Y-266026D01*
X543422Y-261626D01*
G01X540222D02*
X542122Y-266026D01*
G01X547822Y-263359D02*
X551022D01*
X550722Y-262426D01*
X550222Y-261892D01*
X549522Y-261626D01*
X548822Y-261759D01*
X548222Y-262159D01*
X547822Y-263092D01*
X547622Y-263893D01*
Y-264692D01*
X547822Y-265492D01*
X548322Y-266292D01*
X548922Y-266826D01*
X549622Y-266959D01*
X550322Y-266692D01*
X551022Y-265893D01*
G01X555922Y-266959D02*
Y-261626D01*
G01Y-262692D02*
X556422Y-262159D01*
X556922Y-261759D01*
X557622Y-261626D01*
X558122Y-261759D01*
X558722Y-262159D01*
G01X542022Y-316959D02*
Y-308959D01*
X546622Y-316959D01*
Y-308959D01*
G01X552322Y-311626D02*
Y-316959D01*
G01Y-309492D02*
X552122Y-309359D01*
Y-309092D01*
X552322Y-308959D01*
X552522Y-309092D01*
Y-309359D01*
X552322Y-309492D01*
G01X558622Y-316959D02*
Y-311626D01*
G01Y-312959D02*
X559022Y-312292D01*
X559622Y-311759D01*
X560422Y-311626D01*
X561122Y-311759D01*
X561722Y-312292D01*
X562022Y-313226D01*
Y-316959D01*
G01X570122D02*
Y-311626D01*
G01Y-312559D02*
X569722Y-312026D01*
X569122Y-311759D01*
X568422Y-311626D01*
X567722Y-311892D01*
X567122Y-312426D01*
X566722Y-313226D01*
X566522Y-314292D01*
X566722Y-315359D01*
X567122Y-316159D01*
X567722Y-316692D01*
X568422Y-316959D01*
X569122Y-316826D01*
X569722Y-316426D01*
X570122Y-315893D01*
G01X556822Y-283959D02*
Y-291959D01*
G01X554522Y-283959D02*
X559122D01*
G01X564822Y-291959D02*
X564022Y-291826D01*
X563322Y-291292D01*
X562722Y-290492D01*
X562322Y-289559D01*
X562122Y-288492D01*
Y-287426D01*
X562322Y-286359D01*
X562722Y-285426D01*
X563322Y-284626D01*
X564022Y-284092D01*
X564822Y-283959D01*
X565622Y-284092D01*
X566322Y-284626D01*
X566922Y-285426D01*
X567322Y-286359D01*
X567522Y-287426D01*
Y-288492D01*
X567322Y-289559D01*
X566922Y-290492D01*
X566322Y-291292D01*
X565622Y-291826D01*
X564822Y-291959D01*
G01X570822D02*
Y-283959D01*
X573222D01*
X574022Y-284359D01*
X574622Y-285292D01*
X574822Y-286359D01*
X574622Y-287426D01*
X574122Y-288226D01*
X573222Y-288626D01*
X570822D01*
G01X576822Y-266959D02*
Y-258959D01*
X575622Y-260559D01*
G01Y-266959D02*
X578022D01*
G01X649922Y-310292D02*
X650522Y-309492D01*
X651222Y-309092D01*
X652022Y-308959D01*
X653022Y-309226D01*
X653722Y-309892D01*
X653922Y-310692D01*
X653822Y-311493D01*
X653422Y-312159D01*
X651422Y-313492D01*
X650522Y-314426D01*
X649922Y-315759D01*
X649722Y-316959D01*
X653922D01*
G01X659822Y-308959D02*
X659022Y-309226D01*
X658422Y-309892D01*
X658022Y-310692D01*
X657722Y-311759D01*
X657622Y-312959D01*
X657722Y-314159D01*
X658022Y-315226D01*
X658422Y-316026D01*
X659022Y-316692D01*
X659822Y-316959D01*
X660622Y-316692D01*
X661222Y-316026D01*
X661622Y-315226D01*
X661922Y-314159D01*
X662022Y-312959D01*
X661922Y-311759D01*
X661622Y-310692D01*
X661222Y-309892D01*
X660622Y-309226D01*
X659822Y-308959D01*
G01X665922Y-310292D02*
X666522Y-309492D01*
X667222Y-309092D01*
X668022Y-308959D01*
X669022Y-309226D01*
X669722Y-309892D01*
X669922Y-310692D01*
X669822Y-311493D01*
X669422Y-312159D01*
X667422Y-313492D01*
X666522Y-314426D01*
X665922Y-315759D01*
X665722Y-316959D01*
X669922D01*
G01X673922Y-310292D02*
X674522Y-309492D01*
X675222Y-309092D01*
X676022Y-308959D01*
X677022Y-309226D01*
X677722Y-309892D01*
X677922Y-310692D01*
X677822Y-311493D01*
X677422Y-312159D01*
X675422Y-313492D01*
X674522Y-314426D01*
X673922Y-315759D01*
X673722Y-316959D01*
X677922D01*
G01X682022Y-317226D02*
X685622Y-308959D01*
G01X691822Y-316959D02*
Y-308959D01*
X690622Y-310559D01*
G01Y-316959D02*
X693022D01*
G01X697922Y-310292D02*
X698522Y-309492D01*
X699222Y-309092D01*
X700022Y-308959D01*
X701022Y-309226D01*
X701722Y-309892D01*
X701922Y-310692D01*
X701822Y-311493D01*
X701422Y-312159D01*
X699422Y-313492D01*
X698522Y-314426D01*
X697922Y-315759D01*
X697722Y-316959D01*
X701922D01*
G01X706022Y-317226D02*
X709622Y-308959D01*
G01X715822D02*
X715022Y-309226D01*
X714422Y-309892D01*
X714022Y-310692D01*
X713722Y-311759D01*
X713622Y-312959D01*
X713722Y-314159D01*
X714022Y-315226D01*
X714422Y-316026D01*
X715022Y-316692D01*
X715822Y-316959D01*
X716622Y-316692D01*
X717222Y-316026D01*
X717622Y-315226D01*
X717922Y-314159D01*
X718022Y-312959D01*
X717922Y-311759D01*
X717622Y-310692D01*
X717222Y-309892D01*
X716622Y-309226D01*
X715822Y-308959D01*
G01X722122Y-316026D02*
X722822Y-316692D01*
X723622Y-316959D01*
X724422Y-316692D01*
X725122Y-315893D01*
X725622Y-314692D01*
X725822Y-313492D01*
Y-312026D01*
X725622Y-310826D01*
X725122Y-309759D01*
X724522Y-309226D01*
X723822Y-308959D01*
X723022Y-309226D01*
X722422Y-309759D01*
X722022Y-310559D01*
X721822Y-311626D01*
X722022Y-312559D01*
X722522Y-313492D01*
X723122Y-314026D01*
X723822Y-314159D01*
X724622Y-313893D01*
X725222Y-313226D01*
X725822Y-312026D01*
G01X649622Y-291959D02*
Y-283959D01*
X651622D01*
X652422Y-284359D01*
X653022Y-284892D01*
X653522Y-285692D01*
X653922Y-286626D01*
X654022Y-287959D01*
X653922Y-289292D01*
X653522Y-290226D01*
X653022Y-291026D01*
X652422Y-291559D01*
X651622Y-291959D01*
X649622D01*
G01X657322D02*
X659822Y-283959D01*
X662322Y-291959D01*
G01X661422Y-289159D02*
X658222D01*
G01X667822Y-283959D02*
X667022Y-284226D01*
X666422Y-284892D01*
X666022Y-285692D01*
X665722Y-286759D01*
X665622Y-287959D01*
X665722Y-289159D01*
X666022Y-290226D01*
X666422Y-291026D01*
X667022Y-291692D01*
X667822Y-291959D01*
X668622Y-291692D01*
X669222Y-291026D01*
X669622Y-290226D01*
X669922Y-289159D01*
X670022Y-287959D01*
X669922Y-286759D01*
X669622Y-285692D01*
X669222Y-284892D01*
X668622Y-284226D01*
X667822Y-283959D01*
G01X673922Y-291959D02*
Y-283959D01*
X677722D01*
G01X676322Y-287826D02*
X673922D01*
G01X683822Y-283959D02*
X683022Y-284226D01*
X682422Y-284892D01*
X682022Y-285692D01*
X681722Y-286759D01*
X681622Y-287959D01*
X681722Y-289159D01*
X682022Y-290226D01*
X682422Y-291026D01*
X683022Y-291692D01*
X683822Y-291959D01*
X684622Y-291692D01*
X685222Y-291026D01*
X685622Y-290226D01*
X685922Y-289159D01*
X686022Y-287959D01*
X685922Y-286759D01*
X685622Y-285692D01*
X685222Y-284892D01*
X684622Y-284226D01*
X683822Y-283959D01*
G01X691822D02*
Y-291959D01*
G01X689522Y-283959D02*
X694122D01*
G01X697922Y-291959D02*
Y-283959D01*
X701722D01*
G01X700322Y-287826D02*
X697922D01*
G01X708622Y-287692D02*
X709022Y-287292D01*
X709322Y-286626D01*
X709522Y-285692D01*
X709322Y-284892D01*
X708922Y-284359D01*
X708222Y-283959D01*
X705522D01*
Y-291959D01*
X708822D01*
X709522Y-291426D01*
X709922Y-290626D01*
X710122Y-289692D01*
X709922Y-288759D01*
X709322Y-287959D01*
X708622Y-287692D01*
X705522D01*
G01X713922Y-288626D02*
X714622Y-287692D01*
X715222Y-287159D01*
X716022Y-286892D01*
X716722Y-287159D01*
X717222Y-287692D01*
X717622Y-288492D01*
X717722Y-289426D01*
X717622Y-290226D01*
X717222Y-291026D01*
X716622Y-291692D01*
X715922Y-291959D01*
X715122Y-291692D01*
X714422Y-290893D01*
X714022Y-289692D01*
X713922Y-288359D01*
X714122Y-286626D01*
X714422Y-285692D01*
X714922Y-284759D01*
X715622Y-284092D01*
X716322Y-283959D01*
X717022Y-284226D01*
X717522Y-284892D01*
G01X721622Y-291959D02*
Y-283959D01*
X723622D01*
X724422Y-284359D01*
X725022Y-284892D01*
X725522Y-285692D01*
X725922Y-286626D01*
X726022Y-287959D01*
X725922Y-289292D01*
X725522Y-290226D01*
X725022Y-291026D01*
X724422Y-291559D01*
X723622Y-291959D01*
X721622D01*
G01X731822Y-283959D02*
X731022Y-284226D01*
X730422Y-284892D01*
X730022Y-285692D01*
X729722Y-286759D01*
X729622Y-287959D01*
X729722Y-289159D01*
X730022Y-290226D01*
X730422Y-291026D01*
X731022Y-291692D01*
X731822Y-291959D01*
X732622Y-291692D01*
X733222Y-291026D01*
X733622Y-290226D01*
X733922Y-289159D01*
X734022Y-287959D01*
X733922Y-286759D01*
X733622Y-285692D01*
X733222Y-284892D01*
X732622Y-284226D01*
X731822Y-283959D01*
G01X649862Y-270000D02*
Y-263700D01*
X652838D01*
G01X651742Y-266745D02*
X649862D01*
G01X657650Y-263700D02*
X657023Y-263910D01*
X656553Y-264435D01*
X656240Y-265065D01*
X656005Y-265905D01*
X655927Y-266850D01*
X656005Y-267795D01*
X656240Y-268635D01*
X656553Y-269265D01*
X657023Y-269790D01*
X657650Y-270000D01*
X658277Y-269790D01*
X658747Y-269265D01*
X659060Y-268635D01*
X659295Y-267795D01*
X659373Y-266850D01*
X659295Y-265905D01*
X659060Y-265065D01*
X658747Y-264435D01*
X658277Y-263910D01*
X657650Y-263700D01*
G01X663950D02*
Y-270000D01*
G01X662148Y-263700D02*
X665752D01*
G01X667900Y-272100D02*
X672600D01*
G01X674983Y-270000D02*
Y-263700D01*
X676863D01*
X677490Y-264015D01*
X677960Y-264750D01*
X678117Y-265590D01*
X677960Y-266430D01*
X677568Y-267060D01*
X676863Y-267375D01*
X674983D01*
G01X684573Y-264225D02*
X684103Y-263910D01*
X683555Y-263700D01*
X682928D01*
X682223Y-264015D01*
X681675Y-264540D01*
X681283Y-265170D01*
X680970Y-266220D01*
X680892Y-267165D01*
X681048Y-268110D01*
X681283Y-268740D01*
X681753Y-269370D01*
X682302Y-269790D01*
X682850Y-270000D01*
X683398D01*
X683947Y-269790D01*
X684417Y-269475D01*
X684808Y-269055D01*
G01X689777Y-266640D02*
X690090Y-266325D01*
X690325Y-265800D01*
X690482Y-265065D01*
X690325Y-264435D01*
X690012Y-264015D01*
X689463Y-263700D01*
X687348D01*
Y-270000D01*
X689933D01*
X690482Y-269580D01*
X690795Y-268950D01*
X690952Y-268215D01*
X690795Y-267480D01*
X690325Y-266850D01*
X689777Y-266640D01*
X687348D01*
G01X693100Y-272100D02*
X697800D01*
G01X700262Y-270000D02*
Y-263700D01*
X703238D01*
G01X702142Y-266745D02*
X700262D01*
G01X706092Y-270000D02*
X708050Y-263700D01*
X710008Y-270000D01*
G01X709303Y-267795D02*
X706797D01*
G01X712548Y-270000D02*
Y-263700D01*
X716152Y-270000D01*
Y-263700D01*
G01X718300Y-272100D02*
X723000D01*
G01X727577Y-266640D02*
X727890Y-266325D01*
X728125Y-265800D01*
X728282Y-265065D01*
X728125Y-264435D01*
X727812Y-264015D01*
X727263Y-263700D01*
X725148D01*
Y-270000D01*
X727733D01*
X728282Y-269580D01*
X728595Y-268950D01*
X728752Y-268215D01*
X728595Y-267480D01*
X728125Y-266850D01*
X727577Y-266640D01*
X725148D01*
G01X733250Y-270000D02*
X732623Y-269895D01*
X732075Y-269475D01*
X731605Y-268845D01*
X731292Y-268110D01*
X731135Y-267270D01*
Y-266430D01*
X731292Y-265590D01*
X731605Y-264855D01*
X732075Y-264225D01*
X732623Y-263805D01*
X733250Y-263700D01*
X733877Y-263805D01*
X734425Y-264225D01*
X734895Y-264855D01*
X735208Y-265590D01*
X735365Y-266430D01*
Y-267270D01*
X735208Y-268110D01*
X734895Y-268845D01*
X734425Y-269475D01*
X733877Y-269895D01*
X733250Y-270000D01*
G01X737592D02*
X739550Y-263700D01*
X741508Y-270000D01*
G01X740803Y-267795D02*
X738297D01*
G01X744283Y-270000D02*
Y-263700D01*
X746242D01*
X746868Y-264015D01*
X747260Y-264435D01*
X747417Y-265275D01*
X747260Y-266115D01*
X746790Y-266640D01*
X746242Y-266955D01*
X744283D01*
G01X746242D02*
X747417Y-270000D01*
G01X750427D02*
Y-263700D01*
X751993D01*
X752620Y-264015D01*
X753090Y-264435D01*
X753482Y-265065D01*
X753795Y-265800D01*
X753873Y-266850D01*
X753795Y-267900D01*
X753482Y-268635D01*
X753090Y-269265D01*
X752620Y-269685D01*
X751993Y-270000D01*
X750427D01*
G01X756100Y-272100D02*
X760800D01*
G01X762713Y-270000D02*
Y-263700D01*
X764750Y-268950D01*
X766787Y-263700D01*
Y-270000D01*
G01X769483D02*
Y-263700D01*
X771363D01*
X771990Y-264015D01*
X772460Y-264750D01*
X772617Y-265590D01*
X772460Y-266430D01*
X772068Y-267060D01*
X771363Y-267375D01*
X769483D01*
G01X775627Y-269055D02*
X776097Y-269580D01*
X776645Y-269895D01*
X777350Y-270000D01*
X778055Y-269790D01*
X778603Y-269370D01*
X778995Y-268635D01*
X779073Y-267795D01*
X778917Y-266955D01*
X778525Y-266430D01*
X777977Y-266010D01*
X777428Y-265905D01*
X776880Y-266010D01*
X776175Y-266430D01*
X776410Y-263700D01*
X778525D01*
G01X783650D02*
X783023Y-263910D01*
X782553Y-264435D01*
X782240Y-265065D01*
X782005Y-265905D01*
X781927Y-266850D01*
X782005Y-267795D01*
X782240Y-268635D01*
X782553Y-269265D01*
X783023Y-269790D01*
X783650Y-270000D01*
X784277Y-269790D01*
X784747Y-269265D01*
X785060Y-268635D01*
X785295Y-267795D01*
X785373Y-266850D01*
X785295Y-265905D01*
X785060Y-265065D01*
X784747Y-264435D01*
X784277Y-263910D01*
X783650Y-263700D01*
G01X790890Y-270000D02*
Y-263700D01*
X787992Y-268215D01*
X791908D01*
G01X796250Y-270000D02*
X796798Y-269895D01*
X797425Y-269580D01*
X797817Y-269055D01*
X797973Y-268320D01*
X797817Y-267585D01*
X797347Y-266955D01*
X796642Y-266640D01*
X795858D01*
X795388Y-266430D01*
X794997Y-265905D01*
X794840Y-265170D01*
X795075Y-264435D01*
X795623Y-263910D01*
X796250Y-263700D01*
X796877Y-263910D01*
X797425Y-264435D01*
X797660Y-265170D01*
X797503Y-265905D01*
X797112Y-266430D01*
X796642Y-266640D01*
X795858D01*
X795153Y-266955D01*
X794683Y-267585D01*
X794527Y-268320D01*
X794683Y-269055D01*
X795075Y-269580D01*
X795702Y-269895D01*
X796250Y-270000D01*
G01X738322Y-319959D02*
Y-311959D01*
X737122Y-313559D01*
G01Y-319959D02*
X739522D01*
G01X744422Y-316626D02*
X745122Y-315692D01*
X745722Y-315159D01*
X746522Y-314892D01*
X747222Y-315159D01*
X747722Y-315692D01*
X748122Y-316492D01*
X748222Y-317426D01*
X748122Y-318226D01*
X747722Y-319026D01*
X747122Y-319692D01*
X746422Y-319959D01*
X745622Y-319692D01*
X744922Y-318893D01*
X744522Y-317692D01*
X744422Y-316359D01*
X744622Y-314626D01*
X744922Y-313692D01*
X745422Y-312759D01*
X746122Y-312092D01*
X746822Y-311959D01*
X747522Y-312226D01*
X748022Y-312892D01*
G01X754322Y-320226D02*
X754122Y-320092D01*
Y-319826D01*
X754322Y-319692D01*
X754522Y-319826D01*
Y-320092D01*
X754322Y-320226D01*
G01X760422Y-316626D02*
X761122Y-315692D01*
X761722Y-315159D01*
X762522Y-314892D01*
X763222Y-315159D01*
X763722Y-315692D01*
X764122Y-316492D01*
X764222Y-317426D01*
X764122Y-318226D01*
X763722Y-319026D01*
X763122Y-319692D01*
X762422Y-319959D01*
X761622Y-319692D01*
X760922Y-318893D01*
X760522Y-317692D01*
X760422Y-316359D01*
X760622Y-314626D01*
X760922Y-313692D01*
X761422Y-312759D01*
X762122Y-312092D01*
X762822Y-311959D01*
X763522Y-312226D01*
X764022Y-312892D01*
G01X783322Y-319959D02*
Y-311959D01*
X782122Y-313559D01*
G01Y-319959D02*
X784522D01*
G01X791122D02*
X791322Y-318226D01*
X791622Y-316759D01*
X792022Y-315426D01*
X792522Y-313959D01*
X793322Y-311959D01*
X789322D01*
G01X799322Y-320226D02*
X799122Y-320092D01*
Y-319826D01*
X799322Y-319692D01*
X799522Y-319826D01*
Y-320092D01*
X799322Y-320226D01*
G01X805422Y-313292D02*
X806022Y-312492D01*
X806722Y-312092D01*
X807522Y-311959D01*
X808522Y-312226D01*
X809222Y-312892D01*
X809422Y-313692D01*
X809322Y-314493D01*
X808922Y-315159D01*
X806922Y-316492D01*
X806022Y-317426D01*
X805422Y-318759D01*
X805222Y-319959D01*
X809422D01*
G01X803122Y-294959D02*
Y-286959D01*
X805122D01*
X805922Y-287359D01*
X806522Y-287892D01*
X807022Y-288692D01*
X807422Y-289626D01*
X807522Y-290959D01*
X807422Y-292292D01*
X807022Y-293226D01*
X806522Y-294026D01*
X805922Y-294559D01*
X805122Y-294959D01*
X803122D01*
G54D34*
X42717Y597091D03*
X101772Y180748D03*
Y928779D03*
X160827Y597091D03*
G54D52*
X101339Y587000D03*
X98780D03*
X96220D03*
X93661D03*
X91102D03*
X88543D03*
X85984D03*
X83425D03*
Y610000D03*
X85984D03*
X88543D03*
X91102D03*
X93661D03*
X96220D03*
X98780D03*
X101339D03*
X111575Y587000D03*
X109016D03*
X106457D03*
X103898D03*
Y610000D03*
X106457D03*
X109016D03*
X111575D03*
G54D43*
X77900Y63000D03*
X72100D03*
X76743Y119500D03*
X70943D03*
X78400Y415000D03*
X72600D03*
X77400Y778000D03*
X71600D03*
X76900Y828500D03*
X71100D03*
X76400Y1134000D03*
X70600D03*
X76400Y1191000D03*
X70600D03*
X79600Y858500D03*
X85400D03*
X110400Y121000D03*
X104600D03*
X125100Y461000D03*
Y1192500D03*
X126600Y59500D03*
X132400D03*
X126875Y399500D03*
X132675D03*
X130900Y461000D03*
X132100Y766500D03*
X137900D03*
X126100Y829114D03*
X131900D03*
X126600Y1137500D03*
X132400D03*
X130900Y1192500D03*
X166600Y389000D03*
X172400D03*
G54D16*
X10000Y496500D03*
X17000D03*
X31500Y1220600D03*
X12000Y1221000D03*
X19000D03*
X27500Y1229400D03*
X35500D03*
X169000Y1229900D03*
X191500Y496000D03*
X184500D03*
X191500Y1221000D03*
X184500D03*
X173000Y1221100D03*
X177000Y1229900D03*
G54D25*
X29484Y259500D03*
X16484Y502000D03*
Y511000D03*
Y515500D03*
Y506500D03*
Y520000D03*
X26984Y641000D03*
Y645500D03*
Y660000D03*
Y654000D03*
Y686000D03*
Y680500D03*
Y672500D03*
Y666500D03*
X12484Y734000D03*
X22984D03*
X16484Y723000D03*
Y719000D03*
X12484Y748000D03*
Y741000D03*
X22984Y748000D03*
Y741000D03*
X24984Y981500D03*
Y985500D03*
X35775Y268728D03*
X52484Y293000D03*
X46545Y282728D03*
X35775Y995500D03*
X47045Y1009500D03*
X58027Y75342D03*
X57984Y84192D03*
X66527Y75342D03*
X60045Y283728D03*
X74984Y410000D03*
X66027Y401378D03*
X57984Y429228D03*
X58027Y420378D03*
X66527D03*
X71984Y475000D03*
X62984Y641000D03*
Y660000D03*
Y655400D03*
Y647000D03*
Y685000D03*
Y679000D03*
Y672500D03*
Y666500D03*
X73984Y729000D03*
Y738500D03*
Y734500D03*
X66027Y764764D03*
X57984Y792614D03*
X58027Y783764D03*
X66527D03*
X76984Y834000D03*
X60545Y1010500D03*
X59484Y1020000D03*
X58027Y1147650D03*
X75027Y1142650D03*
X66527Y1147650D03*
X66027Y1128650D03*
X57984Y1164000D03*
X100984Y81551D03*
X88484Y450500D03*
X83484Y672000D03*
Y680000D03*
Y688000D03*
Y696000D03*
Y704000D03*
Y709500D03*
Y715000D03*
X115984Y83500D03*
X124984Y66500D03*
X101984Y493500D03*
Y503500D03*
Y509500D03*
Y521500D03*
Y531500D03*
X115484Y659500D03*
Y663500D03*
X120984Y704000D03*
Y711000D03*
Y718000D03*
Y731000D03*
Y738000D03*
Y745000D03*
X145984Y249000D03*
Y257000D03*
X127484Y435000D03*
X134484Y656500D03*
X125484Y694500D03*
X133484D03*
X138484Y762000D03*
X147484Y980500D03*
X148484Y103342D03*
X148984Y126842D03*
X159466Y268728D03*
X169342Y283728D03*
X161984Y292000D03*
X155842Y282728D03*
X148484Y447228D03*
X148984Y470728D03*
X166984Y720000D03*
Y713000D03*
Y747000D03*
Y740000D03*
Y754000D03*
X148484Y810614D03*
X148984Y834114D03*
X159466Y998649D03*
X169342Y1010500D03*
X148984Y989000D03*
X155842Y1009500D03*
X167984Y1021500D03*
X148484Y1174000D03*
X148984Y1197500D03*
X183984Y663500D03*
Y659500D03*
Y652000D03*
X172984Y684500D03*
Y680500D03*
Y676500D03*
Y672500D03*
Y668500D03*
X178984Y706000D03*
X172984Y696500D03*
Y692500D03*
Y688500D03*
X190984Y706000D03*
X178984Y733000D03*
X187484D03*
G54D62*
G01X74626Y513224D02*
Y515080D01*
G01X87500Y491000D02*
Y498000D01*
X87224Y498276D01*
Y500626D01*
G01X118000Y519000D02*
X119276Y517724D01*
Y516374D01*
G01X134000Y501000D02*
Y503000D01*
X133224Y503776D01*
X131874D01*
G54D35*
X29000Y694425D03*
Y696984D03*
Y699543D03*
Y702102D03*
Y704661D03*
Y707220D03*
Y709780D03*
Y712339D03*
Y714898D03*
Y717457D03*
Y720016D03*
Y722575D03*
X52000Y709780D03*
Y707220D03*
Y704661D03*
Y702102D03*
Y699543D03*
Y696984D03*
Y694425D03*
Y722575D03*
Y720016D03*
Y717457D03*
Y714898D03*
Y712339D03*
X131500Y661425D03*
Y663984D03*
Y666543D03*
Y669102D03*
Y671661D03*
Y674220D03*
Y676780D03*
Y679339D03*
Y681898D03*
Y684457D03*
Y687016D03*
Y689575D03*
X131000Y707323D03*
Y709882D03*
Y712441D03*
Y715000D03*
Y717559D03*
Y720118D03*
Y722677D03*
X131500Y738323D03*
Y740882D03*
Y743441D03*
Y746000D03*
Y748559D03*
Y751118D03*
Y753677D03*
X154500Y663984D03*
Y661425D03*
Y687016D03*
Y684457D03*
Y681898D03*
Y679339D03*
Y676780D03*
Y674220D03*
Y671661D03*
Y669102D03*
Y666543D03*
Y689575D03*
X154000Y709882D03*
Y707323D03*
Y722677D03*
Y720118D03*
Y717559D03*
Y715000D03*
Y712441D03*
X154500Y753677D03*
Y751118D03*
Y748559D03*
Y746000D03*
Y743441D03*
Y740882D03*
Y738323D03*
G54D53*
X101772Y1287047D03*
G54D26*
X12791Y267212D03*
Y993984D03*
X45500Y292484D03*
X55500Y389484D03*
X76500Y70484D03*
X75500Y127484D03*
X71000Y528984D03*
X68000Y576484D03*
X75000D03*
X65000Y1199984D03*
X100000Y122484D03*
X85500Y112484D03*
Y470484D03*
X87500Y486984D03*
X93000Y528984D03*
X87500D03*
X80000Y567984D03*
X91000Y631484D03*
X87000D03*
X98500D03*
X92500Y642984D03*
X84700D03*
X98500D03*
X88500Y813484D03*
X92500Y848984D03*
X85500Y833484D03*
X88500Y1176484D03*
X85500Y1196484D03*
X109500Y403484D03*
X113500Y481484D03*
X119000D03*
X124500D03*
Y490484D03*
X109000Y481484D03*
X105000Y631484D03*
X121000D03*
X114000D03*
X107000Y642984D03*
X121000D03*
X114000D03*
X111500Y768484D03*
X112500Y1131484D03*
X127000Y74484D03*
Y88484D03*
X136482Y267212D03*
X127500Y421484D03*
X135500Y481484D03*
X130000D03*
Y490484D03*
X135000Y631484D03*
X131000D03*
X138500Y642984D03*
X126500D03*
X127000Y783984D03*
Y796984D03*
X136482Y997133D03*
X127000Y1148484D03*
Y1162484D03*
X138500Y1183484D03*
X154500Y291484D03*
X148500Y390484D03*
G54D17*
X9517Y734000D03*
Y748000D03*
Y741000D03*
X26517Y259500D03*
X13517Y502000D03*
Y511000D03*
Y515500D03*
Y506500D03*
Y520000D03*
X24017Y641000D03*
Y645500D03*
Y660000D03*
Y654000D03*
Y686000D03*
Y680500D03*
Y672500D03*
Y666500D03*
X20017Y734000D03*
X13517Y723000D03*
Y719000D03*
X20017Y748000D03*
Y741000D03*
X22017Y981500D03*
Y985500D03*
X55060Y75342D03*
X55017Y84192D03*
X32808Y268728D03*
X49517Y293000D03*
X43578Y282728D03*
X55017Y429228D03*
X55060Y420378D03*
X55017Y792614D03*
X55060Y783764D03*
X32808Y995500D03*
X44078Y1009500D03*
X55060Y1147650D03*
X55017Y1164000D03*
X63560Y75342D03*
X57078Y283728D03*
X72017Y410000D03*
X63060Y401378D03*
X63560Y420378D03*
X69017Y475000D03*
X60017Y641000D03*
Y660000D03*
Y655400D03*
Y647000D03*
Y685000D03*
Y679000D03*
Y672500D03*
Y666500D03*
X71017Y729000D03*
Y738500D03*
Y734500D03*
X63060Y764764D03*
X63560Y783764D03*
X74017Y834000D03*
X57578Y1010500D03*
X56517Y1020000D03*
X72060Y1142650D03*
X63560Y1147650D03*
X63060Y1128650D03*
X98017Y81551D03*
X85517Y450500D03*
X99017Y493500D03*
Y503500D03*
Y509500D03*
Y521500D03*
Y531500D03*
X80517Y672000D03*
Y680000D03*
Y688000D03*
Y696000D03*
Y704000D03*
Y709500D03*
Y715000D03*
X113017Y83500D03*
X122017Y66500D03*
X124517Y435000D03*
X112517Y659500D03*
Y663500D03*
X118017Y704000D03*
Y711000D03*
X122517Y694500D03*
X118017Y718000D03*
Y731000D03*
Y738000D03*
Y745000D03*
X145517Y103342D03*
X146017Y126842D03*
X143017Y249000D03*
Y257000D03*
X145517Y447228D03*
X146017Y470728D03*
X131517Y656500D03*
X130517Y694500D03*
X135517Y762000D03*
X145517Y810614D03*
X146017Y834114D03*
X144517Y980500D03*
X146017Y989000D03*
X145517Y1174000D03*
X146017Y1197500D03*
X156499Y268728D03*
X166375Y283728D03*
X159017Y292000D03*
X152875Y282728D03*
X170017Y684500D03*
Y680500D03*
Y676500D03*
Y672500D03*
Y668500D03*
Y696500D03*
Y692500D03*
Y688500D03*
X164017Y720000D03*
Y713000D03*
Y747000D03*
Y740000D03*
Y754000D03*
X156499Y998649D03*
X166375Y1010500D03*
X152875Y1009500D03*
X165017Y1021500D03*
X181017Y663500D03*
Y659500D03*
Y652000D03*
X176017Y706000D03*
X188017D03*
X176017Y733000D03*
X184517D03*
G54D44*
X77776Y500626D03*
Y516374D03*
X87224Y500626D03*
X85650D03*
X84075D03*
X82500D03*
X80925D03*
X79350D03*
Y516374D03*
X80925D03*
X82500D03*
X84075D03*
X85650D03*
X87224D03*
X124000Y500626D03*
X122425D03*
X120850D03*
X119276D03*
Y516374D03*
X120850D03*
X122425D03*
X124000D03*
X128724Y500626D03*
X127150D03*
X125575D03*
Y516374D03*
X127150D03*
X128724D03*
G54D45*
X82500Y508500D03*
X124000D03*
G54D54*
X116772Y19685D03*
G54D36*
X30100Y735500D03*
Y740500D03*
Y745500D03*
Y750500D03*
X50900D03*
Y745500D03*
Y740500D03*
Y735500D03*
G54D27*
X12791Y264245D03*
Y991017D03*
X45500Y289517D03*
X55500Y386517D03*
X76500Y67517D03*
X75500Y124517D03*
X71000Y526017D03*
X68000Y573517D03*
X75000D03*
X65000Y1197017D03*
X85500Y109517D03*
X100000Y119517D03*
X85500Y467517D03*
X87500Y484017D03*
X93000Y526017D03*
X87500D03*
X80000Y565017D03*
X92500Y640017D03*
X84700D03*
X98500D03*
X91000Y628517D03*
X87000D03*
X98500D03*
X88500Y810517D03*
X92500Y846017D03*
X85500Y830517D03*
X88500Y1173517D03*
X85500Y1193517D03*
X109500Y400517D03*
X113500Y478517D03*
X119000D03*
X124500D03*
X109000D03*
X124500Y487517D03*
X107000Y640017D03*
X121000D03*
X114000D03*
X105000Y628517D03*
X121000D03*
X114000D03*
X111500Y765517D03*
X112500Y1128517D03*
X127000Y71517D03*
Y85517D03*
X136482Y264245D03*
X127500Y418517D03*
X135500Y478517D03*
X130000D03*
Y487517D03*
X135000Y628517D03*
X131000D03*
X138500Y640017D03*
X126500D03*
X127000Y781017D03*
Y794017D03*
X136482Y994166D03*
X127000Y1145517D03*
Y1159517D03*
X138500Y1180517D03*
X154500Y288517D03*
X148500Y387517D03*
G54D18*
X30315Y41378D03*
Y404764D03*
Y768150D03*
Y1131536D03*
X173228Y111456D03*
Y474842D03*
Y838228D03*
Y1201614D03*
G54D55*
G01X74857Y611575D02*
X78500D01*
G01X82975Y53333D02*
X85917Y56275D01*
X91500D01*
G54D28*
X28579Y508429D03*
X30547D03*
Y524571D03*
X28579D03*
X38421Y508429D03*
Y524571D03*
X32516Y508429D03*
X34484D03*
X36453D03*
Y524571D03*
X34484D03*
X32516D03*
X170047Y509929D03*
X168079D03*
Y526071D03*
X170047D03*
X177921Y509929D03*
X175953D03*
X173984D03*
X172016D03*
Y526071D03*
X173984D03*
X175953D03*
X177921D03*
G54D37*
X15500Y1227850D03*
X12941Y1234150D03*
X18059D03*
X188000Y1228850D03*
X185441Y1235150D03*
X190559D03*
G54D19*
X34252Y64606D03*
Y56732D03*
Y48858D03*
X26378Y64606D03*
Y56732D03*
X34252Y88228D03*
Y80354D03*
Y72480D03*
X26378Y88228D03*
Y80354D03*
Y72480D03*
X34252Y103976D03*
Y96102D03*
X26378Y103976D03*
Y96102D03*
X34252Y412244D03*
Y435866D03*
Y427992D03*
Y420118D03*
X26378Y435866D03*
Y427992D03*
Y420118D03*
X34252Y451614D03*
Y443740D03*
X26378Y451614D03*
Y443740D03*
X34252Y467362D03*
Y459488D03*
X26378Y467362D03*
Y459488D03*
X34252Y775630D03*
Y799252D03*
Y791378D03*
Y783504D03*
X26378Y799252D03*
Y791378D03*
Y783504D03*
X34252Y822874D03*
Y815000D03*
Y807126D03*
X26378Y822874D03*
Y815000D03*
Y807126D03*
X34252Y830748D03*
X26378D03*
X34252Y1146890D03*
Y1139016D03*
X26378Y1146890D03*
X34252Y1170512D03*
Y1162638D03*
Y1154764D03*
X26378Y1170512D03*
Y1162638D03*
Y1154764D03*
X34252Y1194134D03*
Y1186260D03*
Y1178386D03*
X26378Y1194134D03*
Y1186260D03*
Y1178386D03*
X169291Y48858D03*
Y56732D03*
Y64606D03*
Y72480D03*
Y80354D03*
Y88228D03*
Y96102D03*
Y103976D03*
Y412244D03*
Y420118D03*
Y427992D03*
Y435866D03*
Y443740D03*
Y451614D03*
Y459488D03*
Y467362D03*
Y775630D03*
Y783504D03*
Y791378D03*
Y799252D03*
Y807126D03*
Y815000D03*
Y822874D03*
Y830748D03*
Y1139016D03*
Y1146890D03*
Y1154764D03*
Y1162638D03*
Y1170512D03*
Y1178386D03*
Y1186260D03*
Y1194134D03*
X177165Y48858D03*
Y56732D03*
Y64606D03*
Y72480D03*
Y80354D03*
Y88228D03*
Y96102D03*
Y412244D03*
Y420118D03*
Y427992D03*
Y435866D03*
Y443740D03*
Y451614D03*
Y459488D03*
Y775630D03*
Y783504D03*
Y791378D03*
Y799252D03*
Y807126D03*
Y815000D03*
Y822874D03*
Y1139016D03*
Y1146890D03*
Y1154764D03*
Y1162638D03*
Y1170512D03*
Y1178386D03*
Y1186260D03*
G54D46*
X74626Y503776D03*
Y505350D03*
Y506925D03*
Y508500D03*
Y510075D03*
Y511650D03*
Y513224D03*
X90374D03*
Y511650D03*
Y510075D03*
Y508500D03*
Y506925D03*
Y505350D03*
Y503776D03*
X116126D03*
Y505350D03*
Y506925D03*
Y508500D03*
Y510075D03*
Y511650D03*
Y513224D03*
X131874D03*
Y511650D03*
Y510075D03*
Y508500D03*
Y506925D03*
Y505350D03*
Y503776D03*
G54D56*
G01X-22318Y837184D02*
Y1131672D01*
X-23766Y1133120D01*
X-30873D01*
X-32318Y1131675D01*
Y837184D01*
G01X12389Y653509D02*
X8225Y649345D01*
Y557075D01*
X14100Y551200D01*
X94201D01*
X95964Y552963D01*
X115126D01*
X115814Y552275D01*
X140523D01*
X142248Y554000D01*
X177000D01*
X189250Y541750D01*
G01X14925Y660000D02*
Y659653D01*
X5925Y650653D01*
Y555374D01*
X10799Y550500D01*
X11547D01*
X14047Y548000D01*
X119025D01*
X121000Y549975D01*
X143228D01*
X144753Y551500D01*
X175400D01*
X190564Y536336D01*
X191991D01*
G01X14925Y660000D02*
X11540D01*
X5549Y665991D01*
Y696855D01*
X14441Y705747D01*
X21406D01*
X22879Y707220D01*
X29000D01*
G01Y704661D02*
X23573D01*
X22359Y703447D01*
X15394D01*
X7925Y695978D01*
Y669576D01*
X11001Y666500D01*
X14925D01*
G01X48313Y68687D02*
X40126Y60500D01*
X30146D01*
X26378Y56732D01*
G01Y48858D02*
X30128Y52608D01*
X37107D01*
X48341Y63842D01*
X50000D01*
G01X26378Y72480D02*
X30358Y68500D01*
X37308D01*
X49985Y81177D01*
G01X26378Y96102D02*
X30316Y100040D01*
X41040D01*
X45500Y104500D01*
Y114442D01*
X51400Y120342D01*
G01X17200Y124000D02*
X12575D01*
G01X21925D02*
X17200D01*
G01X16873Y257024D02*
Y252732D01*
X18500Y251105D01*
Y248868D01*
X17782Y248150D01*
G01X29390Y246960D02*
X29783Y246567D01*
X37978D01*
X39670Y248259D01*
Y250879D01*
X35049Y255500D01*
X29575D01*
G01X22500Y255425D02*
X21132D01*
X19533Y257024D01*
X16873D01*
G01X29575Y259500D02*
Y255500D01*
G01X27987Y264636D02*
Y261754D01*
X26425Y260192D01*
Y259500D01*
G01X22500Y258575D02*
Y259637D01*
X24905Y262042D01*
Y263857D01*
X25684Y264636D01*
X27987D01*
G01X26425Y255500D02*
Y252350D01*
X25575Y251500D01*
G01X36880Y249217D02*
X35562D01*
X33279Y251500D01*
X25575D01*
G01X19216Y262728D02*
X17953Y263991D01*
Y267500D01*
G01X21500D02*
Y265500D01*
X22366Y264634D01*
Y262728D01*
G01X29820Y379910D02*
X34510Y384600D01*
X37000D01*
G01X16575Y393000D02*
X19000Y390575D01*
Y380500D01*
X20500Y379000D01*
X28910D01*
X29820Y379910D01*
G01X14600Y387500D02*
Y390600D01*
X16575Y392575D01*
Y393000D01*
G01X46500Y416000D02*
X30134D01*
X26378Y412244D01*
G01Y420118D02*
X27538D01*
X31490Y424070D01*
X46298D01*
X46500Y423868D01*
G01Y432116D02*
X46164Y431780D01*
X30464D01*
X26378Y435866D01*
G01X46500Y463378D02*
X30268D01*
X26378Y459488D01*
G01X16575Y502000D02*
Y506500D01*
G01X48217Y480500D02*
X46320D01*
X28579Y498241D01*
Y508429D01*
G01X41196Y489754D02*
X30547Y500403D01*
Y508429D01*
G01X19700Y487000D02*
X15075D01*
G01X19700D02*
X24425D01*
G01X25429Y517484D02*
X21766D01*
X20375Y518875D01*
G01X25429Y511579D02*
X24549D01*
X21320Y508350D01*
Y506500D01*
G01D02*
X16575D01*
G01Y511000D02*
Y515500D01*
G01D02*
X18499D01*
X20452Y513547D01*
G01D02*
X25429D01*
G01X27580Y528341D02*
X28579Y527342D01*
Y524571D01*
G01X16580Y526220D02*
X18801Y523999D01*
X19000D01*
X23546Y519453D01*
X25429D01*
G01X22100Y526120D02*
Y525560D01*
X25429Y522231D01*
Y521421D01*
G01X72500Y541500D02*
X72000Y541000D01*
X53309D01*
X48238Y538900D01*
X25400D01*
X23000Y536500D01*
Y534075D01*
G01X75396Y544500D02*
X52612D01*
X47541Y542400D01*
X23900D01*
X19000Y537500D01*
Y534075D01*
G01X27000Y530925D02*
X27091Y531016D01*
X32909D01*
X33000Y530925D01*
G01X27000D02*
Y528921D01*
X27580Y528341D01*
G01X19000Y530925D02*
X16580Y528505D01*
Y526220D01*
G01X23000Y530925D02*
X22100Y530025D01*
Y526120D01*
G01X61710Y559000D02*
X57950D01*
X44671Y553500D01*
X32300D01*
X28900Y556900D01*
G01X27075Y641000D02*
X29075Y643000D01*
X34819D01*
X35260Y643441D01*
G01X27075Y641000D02*
Y640402D01*
X22723Y636050D01*
X21070D01*
G01D02*
X19719D01*
X18075Y637694D01*
Y641000D01*
G01X12000D02*
X14925D01*
G01X18075Y645500D02*
X21075Y648500D01*
X24478D01*
X27075Y645903D01*
G01D02*
Y645500D01*
G01X35260Y648559D02*
X35029Y648790D01*
X30850D01*
X30380Y648320D01*
G01D02*
X27963Y645903D01*
X27075D01*
G01X18075Y654000D02*
X20725Y651350D01*
X25023D01*
X27075Y653402D01*
Y654000D01*
G01D02*
X34819D01*
X35260Y654441D01*
G01X18075Y660000D02*
X20725Y657350D01*
X25023D01*
X27075Y659402D01*
Y660000D01*
G01D02*
X32720D01*
G01X14925Y654000D02*
X12880D01*
X12389Y653509D01*
G01X14925Y645500D02*
X13425Y647000D01*
X12525D01*
X12512Y647013D01*
G01X27075Y666500D02*
Y665902D01*
X25023Y663850D01*
G01D02*
X20725D01*
X18075Y666500D01*
G01X14925D02*
Y663000D01*
G01X27075Y666500D02*
X34819D01*
X35260Y666941D01*
G01X27075Y672500D02*
X34819D01*
X35260Y672059D01*
G01X27075Y672500D02*
Y671902D01*
X25023Y669850D01*
G01D02*
X20725D01*
X18075Y672500D01*
G01Y680500D02*
Y680400D01*
X20475Y678000D01*
X25975D01*
X27075Y679100D01*
Y680500D01*
G01D02*
X29999D01*
X31499Y679000D01*
X32728D01*
G01X18075Y686000D02*
Y690093D01*
X19850Y691868D01*
G01D02*
X23763D01*
X27075Y688556D01*
Y686000D01*
G01D02*
X33819D01*
X35260Y684559D01*
G01X14925Y680500D02*
Y680600D01*
G01D02*
X12525Y683000D01*
Y694024D01*
X17348Y698847D01*
X24265D01*
X24961Y699543D01*
X29000D01*
G01X12500Y679000D02*
X13325D01*
X14925Y680600D01*
G01Y669000D02*
Y672500D01*
G01D02*
X10225Y677200D01*
Y695025D01*
X16347Y701147D01*
X23312D01*
X24267Y702102D01*
X29000D01*
G01X14925Y686000D02*
Y690000D01*
G01X20453Y708047D02*
X22186Y709780D01*
X29000D01*
G01Y714898D02*
X19898D01*
X15727Y710727D01*
Y710009D01*
X15713D01*
G01X14925Y690000D02*
Y692425D01*
X19047Y696547D01*
X25218D01*
X25655Y696984D01*
X29000D01*
G01X20327Y711174D02*
X21492Y712339D01*
X29000D01*
G01X21500Y727000D02*
Y724000D01*
X25484Y720016D01*
X29000D01*
G01X16575Y727000D02*
X21500D01*
G01X16575Y723000D02*
Y727000D01*
G01Y715000D02*
Y719000D01*
G01X22000Y718000D02*
X22543Y717457D01*
X29000D01*
G01X16575Y719000D02*
X21000D01*
X22000Y718000D01*
G01X12575Y734000D02*
Y731074D01*
X13375Y730274D01*
G01D02*
X19947D01*
X23075Y733402D01*
Y734000D01*
G01X29000Y728000D02*
Y722575D01*
G01X34425Y727500D02*
X33925Y728000D01*
X29000D01*
G01X19820Y754600D02*
X74899D01*
X90375Y739124D01*
Y736902D01*
X93277Y734000D01*
X95810D01*
X98575Y731235D01*
Y731000D01*
G01X19820Y754600D02*
X15919D01*
X12819Y751500D01*
G01X23075Y734000D02*
Y734460D01*
X29115Y740500D01*
X30100D01*
G01X12575Y748000D02*
X15012Y745563D01*
G01D02*
X15369Y745206D01*
X20879D01*
X23075Y747402D01*
Y748000D01*
G01D02*
X25575Y750500D01*
X30100D01*
G01X12575Y741000D02*
X16391Y737184D01*
X17458D01*
G01D02*
X19857D01*
X23075Y740402D01*
Y741000D01*
G01D02*
X27575Y745500D01*
X30100D01*
G01X12419Y765261D02*
Y838073D01*
X16646Y842300D01*
X77953D01*
X81453Y838800D01*
X99447D01*
X115147Y854500D01*
X146000D01*
G01X14830Y763614D02*
Y837231D01*
X17599Y840000D01*
X77000D01*
X80500Y836500D01*
X100400D01*
X116100Y852200D01*
X147200D01*
X149000Y854000D01*
Y854500D01*
G01X49400Y772264D02*
X46035D01*
X38919Y779380D01*
X30128D01*
X26378Y775630D01*
G01Y783504D02*
X30374Y787500D01*
X36000D01*
X39736Y783764D01*
X46500D01*
G01X46900Y795128D02*
X30502D01*
X26378Y799252D01*
G01Y822874D02*
X30314Y826810D01*
X50712D01*
X50900Y826998D01*
G01X17500Y984075D02*
X18925Y985500D01*
X21925D01*
G01X11433Y983048D02*
X10028Y981643D01*
Y974437D01*
X11403Y973062D01*
X16062D01*
X17500Y974500D01*
G01Y980925D02*
X16188D01*
X14065Y983048D01*
X11433D01*
G01X19925Y974500D02*
Y979500D01*
X21925Y981500D01*
G01X35259Y968798D02*
X34573Y969484D01*
X24516D01*
X19925Y974075D01*
Y974500D01*
G01X28791Y976919D02*
X29000Y977128D01*
Y984000D01*
X27500Y985500D01*
X25075D01*
G01X23075Y974500D02*
X25441Y972134D01*
X27886D01*
G01X17000Y989425D02*
X19575D01*
X20000Y989000D01*
G01X23009Y995491D02*
X20093Y992575D01*
X17000D01*
G01X30522Y1000288D02*
Y997694D01*
X32716Y995500D01*
G01X26378Y1146890D02*
X30138Y1150650D01*
X43500D01*
X46500Y1147650D01*
G01X53900Y1142766D02*
X30128D01*
X26378Y1139016D01*
G01X37300Y1158700D02*
X30314D01*
X26378Y1154764D01*
G01X50900Y1190150D02*
X30268D01*
X26378Y1186260D01*
G01X18059Y1234150D02*
Y1235940D01*
X17075Y1236924D01*
Y1239500D01*
G01X19500D02*
X17075D01*
G01X35500Y1229400D02*
X31600Y1225500D01*
X24000D01*
X21650Y1227850D01*
X15500D01*
G01D02*
X12150D01*
G01X48100Y56342D02*
X54468D01*
G01X34252Y48858D02*
X38358D01*
X45842Y56342D01*
X48100D01*
G01X64543Y57917D02*
X62790D01*
X58915Y54042D01*
X56533D01*
X54468Y56107D01*
Y56342D01*
G01X34252Y64606D02*
X38914D01*
X48184Y73876D01*
G01D02*
X54000Y79692D01*
X54925D01*
G01X54968Y75342D02*
Y75107D01*
X57033Y73042D01*
X61168D01*
X63468Y75342D01*
G01X54968D02*
X48313Y68687D01*
G01X50000Y63842D02*
X56243D01*
G01X49985Y81177D02*
X53000Y84192D01*
X54925D01*
G01X34252Y96102D02*
X42602D01*
X49500Y103000D01*
Y109600D01*
G01D02*
X53400Y113500D01*
X55135D01*
X55327Y113692D01*
G01D02*
Y105526D01*
X56428Y104425D01*
X59500D01*
G01X55327Y97500D02*
X50000D01*
G01D02*
X40728Y88228D01*
X34252D01*
G01X55327Y97500D02*
Y90425D01*
X56327Y89425D01*
X59500D01*
G01X51400Y120342D02*
X56743D01*
G01X41864Y265636D02*
X39272Y268228D01*
X36366D01*
X35866Y268728D01*
G01X32716Y273500D02*
Y268728D01*
G01X43486Y277728D02*
X42986Y278228D01*
X40274D01*
X38383Y280119D01*
G01X44500Y272767D02*
Y275000D01*
X46636Y277136D01*
Y277728D01*
G01X45500Y292575D02*
X49000D01*
X49425Y293000D01*
G01X45500Y298350D02*
Y292575D01*
G01Y289425D02*
X49000D01*
X49425Y289000D01*
G01X52000Y298528D02*
X46878Y303650D01*
X43609D01*
X42350Y302391D01*
Y297581D01*
X43200Y296731D01*
Y291322D01*
X45097Y289425D01*
X45500D01*
G01X52575Y289000D02*
Y288082D01*
X51446Y286953D01*
Y284336D01*
X51956Y283826D01*
G01X56500Y289425D02*
Y286885D01*
X53441Y283826D01*
X51956D01*
G01X44500Y301500D02*
X45500Y300500D01*
Y298350D01*
G01X50150Y385441D02*
X54516D01*
X55500Y386425D01*
G01X43850Y388000D02*
X40450Y384600D01*
X37000D01*
G01X54468Y401378D02*
Y401969D01*
X56499Y404000D01*
X60346D01*
X62968Y401378D01*
G01X54468D02*
X49800D01*
G01D02*
X38934Y412244D01*
X34252D01*
G01X58870Y415378D02*
X56612D01*
X55990Y416000D01*
X46500D01*
G01X54968Y420378D02*
Y420143D01*
X56783Y418328D01*
X56915D01*
X57165Y418078D01*
X62244D01*
X63468Y419302D01*
Y419780D01*
G01X54968Y420378D02*
X52672D01*
X49182Y423868D01*
X46500D01*
G01X54925Y429228D02*
X52037Y432116D01*
X46500D01*
G01X54925Y424728D02*
X53272D01*
X50000Y428000D01*
G01D02*
X49992Y427992D01*
X34252D01*
G01X54827Y457228D02*
X54500Y456901D01*
Y450225D01*
X55800Y448925D01*
X59500D01*
G01X46500Y451614D02*
X34252D01*
G01X54827Y443728D02*
X54386D01*
X46500Y451614D01*
G01X54827Y443728D02*
X54500Y443401D01*
Y436225D01*
X55800Y434925D01*
X59500D01*
G01X58425Y475000D02*
X50486D01*
X49689Y474203D01*
G01X56243Y463878D02*
X55743Y463378D01*
X46500D01*
G01X34252Y459488D02*
X36512Y457228D01*
X49200D01*
G01D02*
X54827D01*
G01X53850Y480500D02*
X48217D01*
G01X53775Y485500D02*
X45450D01*
X41196Y489754D01*
G01X53775Y490500D02*
X49023D01*
G01D02*
X45000D01*
X32516Y502984D01*
Y508429D01*
G01X53775Y495500D02*
X45953D01*
G01D02*
X43500D01*
X34484Y504516D01*
Y508429D01*
G01X53775Y500500D02*
X48872D01*
G01D02*
X42000D01*
X36453Y506047D01*
Y508429D01*
G01X49250Y516750D02*
X48016Y515516D01*
X41571D01*
G01X38421Y508429D02*
Y507579D01*
X40940Y505060D01*
X44140D01*
G01X53775Y506000D02*
X52605Y504830D01*
X44370D01*
X44140Y505060D01*
G01X48970Y507700D02*
X46300D01*
X42421Y511579D01*
X41571D01*
G01X53775Y511000D02*
X50475Y507700D01*
X48970D01*
G01X53775Y516000D02*
X51322Y513547D01*
X49627D01*
X48940Y512860D01*
X47140D01*
G01D02*
X46453Y513547D01*
X41571D01*
G01X53775Y521000D02*
X49650D01*
X48500Y519850D01*
G01D02*
X46134Y517484D01*
X41571D01*
G01X49120Y526000D02*
Y525060D01*
X43513Y519453D01*
X41571D01*
G01X43450Y528170D02*
X41571Y526291D01*
Y521421D01*
G01X38421Y524571D02*
Y527751D01*
X45250Y534580D01*
X47865D01*
G01X53775Y526000D02*
X49120D01*
G01X53775Y531000D02*
X46280D01*
X43450Y528170D01*
G01X53850Y536000D02*
X52430Y534580D01*
X47865D01*
G01X42740Y643441D02*
X43181Y643000D01*
X48499D01*
X50499Y641000D01*
X50925D01*
G01D02*
Y641598D01*
X52977Y643650D01*
X57275D01*
X59925Y641000D01*
G01X47499Y649000D02*
X43181D01*
X42740Y648559D01*
G01X47499Y649000D02*
X49499Y647000D01*
X50925D01*
G01D02*
Y647598D01*
X52977Y649650D01*
X57275D01*
X59925Y647000D01*
G01X52977Y662650D02*
X57275D01*
X59925Y660000D01*
G01X52977Y662650D02*
X50925Y660598D01*
Y660000D01*
G01D02*
X43181D01*
X42740Y659559D01*
G01X32720Y660000D02*
X34819D01*
X35260Y659559D01*
G01X42740Y654441D02*
X43181Y654000D01*
X50925D01*
G01D02*
Y654598D01*
X53454Y657127D01*
X58282D01*
X59925Y655484D01*
Y655400D01*
G01X50925Y666500D02*
Y667098D01*
X52977Y669150D01*
X57275D01*
X59925Y666500D01*
G01X50925D02*
X46950D01*
G01D02*
X43181D01*
X42740Y666941D01*
G01X50925Y672500D02*
Y673098D01*
X52977Y675150D01*
X57275D01*
X59925Y672500D01*
G01X50925D02*
X46950D01*
G01D02*
X43181D01*
X42740Y672059D01*
G01Y679441D02*
X43181Y679000D01*
X50925D01*
G01X59925D02*
X57275Y681650D01*
X52977D01*
G01D02*
X50925Y679598D01*
Y679000D01*
G01X42740Y684559D02*
X43181Y685000D01*
X50925D01*
G01X54160Y689760D02*
X52765D01*
X50925Y687920D01*
Y685000D01*
G01X35260Y679441D02*
X34819Y679000D01*
X32728D01*
G01X59925Y685000D02*
X55165Y689760D01*
X54160D01*
G01X60500Y693500D02*
X60125Y693956D01*
X55366Y694425D01*
X52000D01*
G01Y696984D02*
X60000D01*
G01X65610Y700000D02*
X57500D01*
X56397Y699543D01*
X52000D01*
G01Y704661D02*
X60260D01*
G01X65920Y708260D02*
X57600D01*
X56560Y707220D01*
X52000D01*
G01Y709780D02*
X55500D01*
X57660Y711940D01*
X69350D01*
G01X52000Y720016D02*
X59916D01*
X65100Y725200D01*
G01X68100Y721000D02*
X66199D01*
X62656Y717457D01*
X52000D01*
G01Y714898D02*
X65768D01*
X65870Y715000D01*
G01X58612Y740500D02*
X50900D01*
G01X65570Y734500D02*
X61501D01*
X60501Y735500D01*
X50900D01*
G01Y745500D02*
X55572D01*
X57161Y747089D01*
X65087D01*
G01X34000Y757000D02*
X36200Y759200D01*
X88000D01*
X96523Y750677D01*
Y747650D01*
X98575Y745598D01*
Y745000D01*
G01X37000Y756900D02*
X76100D01*
X92000Y741000D01*
X96173D01*
X98575Y738598D01*
Y738000D01*
G01X56243Y772264D02*
X49400D01*
G01X55327Y778500D02*
Y775174D01*
X56243Y774258D01*
Y772264D01*
G01X62968Y764764D02*
X60668Y767064D01*
X56533D01*
X54468Y764999D01*
Y764764D01*
G01D02*
X49800D01*
G01D02*
X38934Y775630D01*
X34252D01*
G01X54925Y788114D02*
X50785D01*
X49199Y789700D01*
X47100D01*
G01D02*
X39300D01*
X37622Y791378D01*
X34252D01*
G01X54968Y783764D02*
Y783529D01*
X56783Y781714D01*
X56915D01*
X57165Y781464D01*
X62244D01*
X63468Y782688D01*
Y783166D01*
G01X46500Y783764D02*
X54968D01*
G01X54925Y792614D02*
X51885D01*
X49371Y795128D01*
X46900D01*
G01X57500Y801075D02*
X56886D01*
X53736Y797925D01*
X53500D01*
G01X52800Y813500D02*
X62000D01*
X65000Y810500D01*
X71223D01*
X73384Y808339D01*
X79868D01*
X81207Y807000D01*
X88490D01*
X89520Y805970D01*
X95980D01*
G01X54827Y820614D02*
X46500D01*
G01D02*
X39386D01*
X37126Y822874D01*
X34252D01*
G01X54827Y820614D02*
X54925Y820516D01*
Y816000D01*
G01X34252Y815000D02*
X38400D01*
X46900Y806500D01*
G01D02*
X49200D01*
X52600Y809900D01*
X54827D01*
G01D02*
X54925Y809802D01*
Y805000D01*
G01X54827Y809900D02*
Y810000D01*
G01X66925Y834000D02*
X64425Y836500D01*
X51300D01*
X47813Y833013D01*
G01X50900Y826998D02*
X55977D01*
X56243Y827264D01*
G01X35866Y995500D02*
X36366Y995000D01*
X40500D01*
G01X43986Y1004500D02*
X43486Y1005000D01*
X39061D01*
G01X47136Y1004500D02*
Y1005500D01*
X48492Y1006856D01*
G01X44100Y1027850D02*
X44916Y1028666D01*
X57334D01*
X59575Y1026425D01*
Y1024000D01*
G01X50000Y1023000D02*
Y1018500D01*
X52500Y1016000D01*
X56425D01*
G01X54968Y1147650D02*
Y1147415D01*
X56783Y1145600D01*
X56915D01*
X57165Y1145350D01*
X62244D01*
X63468Y1146574D01*
Y1147052D01*
G01X46500Y1147650D02*
X54968D01*
G01X58870Y1142650D02*
X58754Y1142766D01*
X53900D01*
G01X62968Y1128650D02*
X60918Y1130700D01*
X56283D01*
X54468Y1128885D01*
Y1128650D01*
G01D02*
X46409Y1136709D01*
G01D02*
X44102Y1139016D01*
X34252D01*
G01X49400Y1153000D02*
X47636Y1154764D01*
X34252D01*
G01X54925Y1152000D02*
X50400D01*
X49400Y1153000D01*
G01X54925Y1168500D02*
Y1171152D01*
X54827Y1171250D01*
Y1173500D01*
G01X54925Y1164000D02*
X52501D01*
X50001Y1166500D01*
X47000D01*
G01X40500Y1164000D02*
X43000Y1166500D01*
X47000D01*
G01X58075Y1160000D02*
X56875Y1158800D01*
Y1158565D01*
X54925Y1156615D01*
Y1156000D01*
G01X56243Y1190650D02*
X55743Y1190150D01*
X50900D01*
G01X54827Y1184000D02*
X46500D01*
G01D02*
X41000D01*
X38740Y1186260D01*
X34252D01*
G01X54925Y1178500D02*
Y1183902D01*
X54827Y1184000D01*
G01X49764Y1175063D02*
X46441Y1178386D01*
X34252D01*
G01X54827Y1173500D02*
X51327D01*
X49764Y1175063D01*
G01X36075Y1235500D02*
X40600D01*
X40700Y1235600D01*
G01D02*
X40800Y1235500D01*
X41400D01*
X42500Y1234400D01*
Y1231000D01*
X40900Y1229400D01*
X35500D01*
G01X93075Y72000D02*
X88425Y67350D01*
Y63500D01*
X83925Y59000D01*
X70005D01*
X68131Y60874D01*
X59519D01*
X57618Y58973D01*
Y56342D01*
G01X64543Y57917D02*
X67835D01*
X69410Y56342D01*
X71870D01*
G01X72100Y63000D02*
X72500Y63400D01*
Y67425D01*
G01X68416Y63842D02*
X69258Y63000D01*
X72100D01*
G01X58118Y75342D02*
X59842D01*
X62937Y78437D01*
X69710D01*
X72041Y80768D01*
X73877D01*
G01D02*
X94232D01*
X98441Y76559D01*
X99260D01*
G01X58075Y79692D02*
X60475D01*
G01X58075Y84192D02*
X61000D01*
G01X71827Y75192D02*
Y74827D01*
X69500Y72500D01*
X65712D01*
X63468Y74744D01*
Y75342D01*
G01X56243Y63842D02*
Y67715D01*
X58870Y70342D01*
G01X71650Y86441D02*
X76516D01*
X77000Y86925D01*
G01X72500Y70575D02*
X71076D01*
X70501Y70000D01*
X68500D01*
G01X68416Y63842D02*
X64843D01*
G01X72500Y67425D02*
X72575Y67500D01*
X74449D01*
X74466Y67517D01*
X76408D01*
X76500Y67425D01*
G01X65425Y81000D02*
Y86675D01*
X65350Y86750D01*
Y89000D01*
G01X77000Y86925D02*
X79500D01*
G01Y104425D02*
X77000D01*
G01D02*
X76016Y103441D01*
X71650D01*
G01X64025Y92575D02*
X65350Y91250D01*
Y89000D01*
G01X59500Y92575D02*
X64025D01*
G01X59500Y107575D02*
X61028D01*
X62603Y106000D01*
X65350D01*
G01Y102000D02*
Y106000D01*
G01X65425Y98000D02*
X65350Y98075D01*
Y102000D01*
G01X71500Y127575D02*
Y130000D01*
G01X59370Y126842D02*
X56743Y124215D01*
Y120342D01*
G01X71500Y124425D02*
X75500D01*
G01X70943Y119500D02*
X71500Y120057D01*
Y124425D01*
G01X65343Y120342D02*
Y116217D01*
X67310Y114250D01*
G01D02*
X69551D01*
X70943Y115642D01*
Y119500D01*
G01X64500Y287000D02*
X61500D01*
X60136Y285636D01*
Y283728D01*
G01X56986D02*
Y282803D01*
X58561Y281228D01*
Y280728D01*
G01X61420Y299310D02*
Y297495D01*
X56500Y292575D01*
G01X55500Y386425D02*
X59075D01*
X60000Y385500D01*
X78500D01*
X82500Y389500D01*
G01X89169Y401350D02*
X81850D01*
X75500Y395000D01*
X63996D01*
X57618Y401378D01*
G01X56243Y408878D02*
X58870Y411505D01*
Y415378D01*
G01X62968Y401378D02*
Y400780D01*
X66448Y397300D01*
X70070D01*
X71870Y399100D01*
Y401378D01*
G01X78500Y406000D02*
X75075D01*
G01X65900Y413000D02*
X64843Y411943D01*
Y408878D01*
G01X71925Y406000D02*
X69975D01*
X68800Y407175D01*
Y411000D01*
X66800Y413000D01*
X65900D01*
G01X71925Y410000D02*
X71968Y409957D01*
Y408093D01*
X71925Y408050D01*
Y406000D01*
G01Y410000D02*
Y414325D01*
X72600Y415000D01*
G01X58118Y420378D02*
X59378D01*
X63000Y424000D01*
X74682D01*
X76682Y426000D01*
G01D02*
X83819D01*
X96260Y413559D01*
G01X58075Y424728D02*
X60475D01*
G01X58075Y429228D02*
X60475D01*
G01X63468Y419780D02*
X65520Y417728D01*
X70116D01*
X71827Y419439D01*
Y420228D01*
G01X63468Y420378D02*
Y419780D01*
G01X71650Y432441D02*
X76984D01*
X77000Y432425D01*
G01D02*
X79463Y429962D01*
G01X65350Y435000D02*
Y432150D01*
X67000Y430500D01*
G01X64925Y427000D02*
X65350Y427425D01*
Y428850D01*
X67000Y430500D01*
G01X58500Y454500D02*
X67000D01*
X68000Y453500D01*
Y447500D01*
X69000Y446500D01*
X85903D01*
X90807Y441596D01*
X106850D01*
G01X79500Y449925D02*
X77000D01*
G01D02*
X75024D01*
X74040Y448941D01*
X71650D01*
G01X58500Y441000D02*
X58834Y440666D01*
X79491D01*
X89657Y430500D01*
X104220D01*
X114295Y420425D01*
X115000D01*
G01X59500Y452075D02*
X64775D01*
X65350Y451500D01*
G01X64925Y443500D02*
X65350Y443925D01*
Y447500D01*
G01D02*
Y451500D01*
G01X59500Y438075D02*
X63425D01*
X65350Y436150D01*
Y435000D01*
G01X56243Y463878D02*
X58870Y466505D01*
Y470378D01*
G01X61575Y475000D02*
X68925D01*
G01X64843Y463878D02*
X68000D01*
G01D02*
Y466500D01*
X70400Y468900D01*
X72000D01*
G01X68925Y475000D02*
Y472575D01*
X72000Y469500D01*
Y468900D01*
G01X57000Y480500D02*
Y483000D01*
G01X56925Y495500D02*
Y498000D01*
G01Y500500D02*
Y503000D01*
G01Y490500D02*
Y493000D01*
G01Y485500D02*
Y488000D01*
G01X60150Y480500D02*
X65300D01*
G01D02*
X71899D01*
X79909Y488510D01*
X82010D01*
X84850Y491350D01*
G01X60075Y485500D02*
X68930D01*
G01D02*
X72499D01*
X77809Y490810D01*
X80971D01*
X83555Y493394D01*
G01X60075Y490500D02*
X65300D01*
G01D02*
X73311D01*
X75921Y493110D01*
X80018D01*
X82500Y495592D01*
G01X60075Y495500D02*
X70080D01*
X70460Y495120D01*
G01D02*
X70840Y495500D01*
X77486D01*
G01X60075Y500500D02*
X62524Y498051D01*
X64541D01*
X64680Y498190D01*
X64700D01*
G01D02*
X64839Y498051D01*
X76809D01*
G01X69290Y500790D02*
X75662D01*
X75902Y500550D01*
G01X60075Y506000D02*
X65285Y500790D01*
X69290D01*
G01X56925Y511000D02*
Y513500D01*
G01X71000Y525925D02*
X73240Y523685D01*
X75868D01*
G01X56925Y506000D02*
Y508500D01*
G01Y521000D02*
Y523500D01*
G01Y516000D02*
Y518500D01*
G01X79293Y523513D02*
X76881Y525925D01*
G01X65479Y504809D02*
X66838Y503450D01*
X68970D01*
G01X60075Y511000D02*
Y510220D01*
X65479Y504810D01*
Y504809D01*
G01X64800Y510030D02*
X66791Y508039D01*
X67128D01*
G01X60075Y516000D02*
X63479Y512596D01*
Y511351D01*
X64800Y510030D01*
G01X66903Y512164D02*
Y514172D01*
X66290Y514785D01*
Y515220D01*
G01X60075Y521000D02*
X65855Y515220D01*
X66290D01*
G01X64820Y520300D02*
X66406Y518714D01*
X67094D01*
G01X60075Y526000D02*
Y525045D01*
X64820Y520300D01*
G01X68721Y520340D02*
X64710Y524351D01*
Y525630D01*
G01X60075Y531000D02*
X63000Y528075D01*
Y527342D01*
X64710Y525630D01*
G01X64945Y534505D02*
X66000Y533450D01*
Y528554D01*
G01X75650Y517770D02*
Y517384D01*
X76660Y516374D01*
G01X56925Y531000D02*
Y533500D01*
G01X71000Y525925D02*
X70500Y526425D01*
X69902D01*
X68350Y527977D01*
Y533260D01*
X68345Y533265D01*
G01D02*
X69005Y533925D01*
X71000D01*
G01X57000Y536000D02*
Y538500D01*
G01X56925Y526000D02*
Y528500D01*
G01X108000Y539500D02*
X106500Y541000D01*
X73000D01*
X72500Y541500D01*
G01X109000Y543500D02*
X108000Y544500D01*
X75396D01*
G01X76500Y525925D02*
X76881D01*
G01D02*
X77098D01*
X79150Y527977D01*
Y532275D01*
X77500Y533925D01*
X76500D01*
G01X60150Y536000D02*
X63450D01*
X64945Y534505D01*
G01X75000Y568075D02*
X78000Y571075D01*
Y574499D01*
X75924Y576575D01*
X75000D01*
G01X68000D02*
X67402D01*
X65000Y574173D01*
Y569800D01*
X66725Y568075D01*
X68000D01*
G01X80000Y559075D02*
X79925Y559000D01*
X61710D01*
G01X75000Y576575D02*
Y577900D01*
X76100Y579000D01*
X79930D01*
G01X72899Y582500D02*
X71000D01*
X68000Y579500D01*
Y576575D01*
G01X72899Y582500D02*
X80978D01*
X83425Y584947D01*
Y587000D01*
G01X68000Y628425D02*
Y622049D01*
X73285Y616764D01*
G01D02*
X75149Y614900D01*
X84077D01*
X85984Y612993D01*
Y610000D01*
G01X88543D02*
Y613743D01*
X84686Y617600D01*
X78100D01*
X72000Y623700D01*
G01X64480Y636220D02*
X63281D01*
X59925Y639576D01*
Y641000D01*
G01X64480Y636220D02*
X65909D01*
X68925Y639236D01*
Y641000D01*
G01X72075D02*
Y643276D01*
X77763Y648964D01*
X79836D01*
X82716Y646084D01*
X137934D01*
X139500Y647650D01*
X145750D01*
X147500Y645900D01*
X150300D01*
G01X80900Y631575D02*
X80254D01*
X78200Y629521D01*
Y623400D01*
X80400Y621200D01*
G01X78457Y634010D02*
X74435D01*
X72000Y631575D01*
G01X78677Y637315D02*
X77522Y638470D01*
X73269D01*
X68000Y633201D01*
Y631575D01*
G01X72000Y623700D02*
Y628425D01*
G01X59925Y647000D02*
Y647598D01*
X61977Y649650D01*
X66275D01*
X68925Y647000D01*
G01Y657500D02*
X63775Y662650D01*
X61977D01*
X59925Y660598D01*
Y660000D01*
G01X68925Y651500D02*
X68025Y652400D01*
X63070D01*
G01D02*
X61401D01*
X59925Y653876D01*
Y655400D01*
G01X72075Y647000D02*
X76581Y651506D01*
X80894D01*
X84016Y648384D01*
X136934D01*
X138690Y650140D01*
X148980D01*
X149995Y649125D01*
X168167Y641600D01*
X182500D01*
G01X187500Y643500D02*
X187100Y643900D01*
X169652D01*
X151486Y651424D01*
X150250Y652660D01*
X137870D01*
X136210Y651000D01*
X84700D01*
X80700Y655000D01*
X75575D01*
X72075Y651500D01*
G01Y657500D02*
X81799D01*
X85999Y653300D01*
X135060D01*
X136900Y655140D01*
X151230D01*
X153142Y653228D01*
X170110Y646200D01*
X189548D01*
X191259Y644489D01*
Y547500D01*
G01X68000Y664000D02*
X69999D01*
X72075Y666076D01*
Y666500D01*
G01X59925D02*
Y667098D01*
X61977Y669150D01*
X66275D01*
X68925Y666500D01*
G01X59925Y672500D02*
Y673098D01*
X61977Y675150D01*
X65851D01*
X68501Y672500D01*
X68925D01*
G01X59925Y679000D02*
Y679598D01*
X61977Y681650D01*
X66275D01*
X68925Y679000D01*
G01X59925Y685000D02*
Y685598D01*
X61977Y687650D01*
X66275D01*
X68925Y685000D01*
G01X69000Y669745D02*
X70245D01*
X72075Y671575D01*
Y672500D01*
G01X68000Y676500D02*
X70000D01*
X72075Y678575D01*
Y679000D01*
G01Y685000D02*
Y685235D01*
X67360Y689950D01*
X60450D01*
X59475Y688975D01*
G01X60500Y693500D02*
X67063D01*
X75000Y685563D01*
Y679474D01*
X78474Y676000D01*
X80425D01*
G01X60000Y696984D02*
X66832D01*
X79816Y684000D01*
X80425D01*
G01Y692000D02*
X75350D01*
X67350Y700000D01*
X65610D01*
G01X60260Y704661D02*
X66339D01*
X71950Y699050D01*
X78812D01*
X79762Y700000D01*
X80425D01*
G01X70925Y704000D02*
Y703402D01*
X72977Y701350D01*
X77859D01*
X80425Y703916D01*
Y704000D01*
G01X65920Y708260D02*
X66665D01*
X70925Y704000D01*
G01Y709500D02*
Y708902D01*
X72977Y706850D01*
X77859D01*
X80425Y709416D01*
Y709500D01*
G01X69350Y711940D02*
X70925Y710365D01*
Y709500D01*
G01X65100Y725200D02*
X69725D01*
X70925Y724000D01*
G01X68100Y721000D02*
X68925D01*
X70925Y719000D01*
G01X80425Y715000D02*
Y714916D01*
X77859Y712350D01*
X72977D01*
X70925Y714402D01*
Y715000D01*
G01D02*
X65870D01*
G01X74075Y719000D02*
Y721500D01*
G01Y719000D02*
X75871D01*
X81500Y724629D01*
Y733500D01*
X76500Y738500D01*
X74075D01*
G01Y724000D02*
Y726500D01*
G01Y724000D02*
X74879D01*
X78000Y727121D01*
Y732050D01*
X75550Y734500D01*
X74075D01*
G01X70925Y738500D02*
X64001D01*
X62001Y740500D01*
X58612D01*
G01X70925Y734500D02*
X65570D01*
G01X70925Y746500D02*
Y742500D01*
G01D02*
X69676D01*
X65087Y747089D01*
G01X112425Y683500D02*
X109000D01*
X94619Y697881D01*
Y725299D01*
X88075Y731843D01*
Y738150D01*
X76725Y749500D01*
G01X64843Y772264D02*
X66000Y773421D01*
Y776000D01*
G01D02*
Y777925D01*
X66575Y778500D01*
G01X72000Y773075D02*
Y777600D01*
X71600Y778000D01*
G01D02*
X71100Y778500D01*
X66575D01*
G01X57618Y764764D02*
X59012D01*
X61576Y762200D01*
G01X95760Y773441D02*
X83819Y761500D01*
X64326D01*
X63626Y762200D01*
X61576D01*
G01X71870Y764764D02*
Y766314D01*
X70770Y767414D01*
X65020D01*
X63468Y765862D01*
Y765264D01*
X62968Y764764D01*
G01X72000Y769925D02*
X70575D01*
X69000Y771500D01*
G01X58118Y783764D02*
X59764D01*
X62500Y786500D01*
X79500D01*
X81500Y788500D01*
Y789000D01*
G01X58075Y788114D02*
X59164D01*
X61050Y790000D01*
X78050D01*
X84429Y796379D01*
X89385D01*
X94000Y791764D01*
Y787221D01*
X99279Y781942D01*
G01X99500Y787000D02*
X97500Y789000D01*
Y793214D01*
X90835Y799879D01*
X82879D01*
X76500Y793500D01*
X59600D01*
X58714Y792614D01*
X58075D01*
G01X63468Y783166D02*
X65520Y781114D01*
X70116D01*
X71827Y782825D01*
Y783614D01*
G01X63468Y783764D02*
Y783166D01*
G01X77000Y800425D02*
X75134D01*
X71650Y796941D01*
G01X83000Y804000D02*
X82000D01*
X78425Y800425D01*
X77000D01*
G01X62058Y801075D02*
X63633Y799500D01*
X65350D01*
G01X64925Y807500D02*
X65350Y807075D01*
Y799500D01*
G01X62058Y801075D02*
Y803443D01*
X60501Y805000D01*
X58075D01*
G01X77000Y813425D02*
X72134D01*
X71650Y812941D01*
G01X83000Y810000D02*
X79575Y813425D01*
X77000D01*
G01X71425Y823500D02*
X68500D01*
X65350Y820350D01*
Y818654D01*
G01D02*
Y815500D01*
G01D02*
X64850Y816000D01*
X58075D01*
G01X58870Y833764D02*
Y829891D01*
X56243Y827264D01*
G01X64843D02*
X67493D01*
X67993Y827764D01*
G01X70075Y834000D02*
X73925D01*
G01X71100Y828500D02*
Y830399D01*
X70075Y831424D01*
Y834000D01*
G01X67993Y827764D02*
X68729Y828500D01*
X71100D01*
G01X80850Y848500D02*
X78775Y846425D01*
X75500D01*
G01X71410Y846500D02*
X64400D01*
G01X75500Y846425D02*
X75425Y846500D01*
X71410D01*
G01X119500Y992000D02*
X108500Y1003000D01*
X60650D01*
X56150Y1007500D01*
G01X72000Y1013500D02*
X63636D01*
X60636Y1010500D01*
G01X57486D02*
Y1009575D01*
X59268Y1007793D01*
G01X59575Y1020000D02*
Y1024000D01*
G01X63500Y1016425D02*
X63075Y1016000D01*
X59575D01*
G01X63500Y1019575D02*
Y1023084D01*
X62500Y1025500D01*
G01X56425Y1016000D02*
Y1020000D01*
G01X115500Y1148425D02*
X106925D01*
X102000Y1143500D01*
Y1130015D01*
X87253Y1115268D01*
X64231D01*
G01X57618Y1128650D02*
Y1127882D01*
X62000Y1123500D01*
X82000D01*
G01X71870Y1128650D02*
X69220Y1126000D01*
X65020D01*
X62968Y1128052D01*
Y1128650D01*
G01X80000Y1151500D02*
X63500D01*
X59650Y1147650D01*
X58118D01*
G01X63468D02*
Y1147052D01*
G01X71827Y1147500D02*
Y1146711D01*
X70116Y1145000D01*
X65520D01*
X63468Y1147052D01*
G01X58870Y1142650D02*
Y1138777D01*
X56243Y1136150D01*
G01X75075Y1138500D02*
X77518D01*
G01X64843Y1136150D02*
Y1138892D01*
X65944Y1139993D01*
X68686D01*
G01X71968Y1142650D02*
Y1138543D01*
X71925Y1138500D01*
G01X70600Y1134000D02*
X71968Y1135368D01*
Y1138457D01*
X71925Y1138500D01*
G01X68686Y1139993D02*
Y1135914D01*
X70600Y1134000D01*
G01X58075Y1152000D02*
X60475D01*
G01X61500Y1160000D02*
Y1162900D01*
X60400Y1164000D01*
X58075D01*
G01X71150Y1157441D02*
X74434D01*
X74450Y1157425D01*
X76500D01*
G01D02*
X79000D01*
G01X64425Y1165500D02*
X65500Y1164425D01*
Y1160650D01*
X64850Y1160000D01*
G01X64425Y1165500D02*
Y1168000D01*
G01D02*
X62474D01*
X61974Y1168500D01*
X58075D01*
G01X64843Y1194000D02*
Y1190650D01*
G01X65000Y1196925D02*
Y1194157D01*
X64843Y1194000D01*
G01X69425Y1196500D02*
Y1192175D01*
X70600Y1191000D01*
G01X56000Y1197327D02*
Y1195177D01*
X56243Y1194934D01*
Y1190650D01*
G01X71150Y1173441D02*
X74434D01*
X74450Y1173425D01*
X76500D01*
G01D02*
X79000D01*
G01X64425Y1184000D02*
Y1180575D01*
X64850Y1180150D01*
Y1179000D01*
G01D02*
Y1176000D01*
G01X58075Y1178500D02*
Y1178400D01*
X60475Y1176000D01*
X64850D01*
G01X69425Y1196500D02*
X69000Y1196925D01*
X65000D01*
G01X72575Y1196500D02*
X75000D01*
G01X91500Y53125D02*
Y47450D01*
X94492Y44458D01*
Y29392D01*
X92992Y27892D01*
Y17126D01*
G01X102500Y53125D02*
X100424D01*
X96700Y49401D01*
Y47200D01*
X97992Y45908D01*
Y17126D01*
G01X91500Y53125D02*
X96000D01*
G01X99000Y61000D02*
X96257Y56896D01*
X96000Y56275D01*
G01X99883Y57500D02*
X101275D01*
X102500Y56275D01*
G01X99260Y71441D02*
X98701Y72000D01*
X93075D01*
G01X87500Y83300D02*
X96176D01*
X97925Y81551D01*
G01X112000Y88700D02*
X107529Y84229D01*
X102175D01*
X101075Y83129D01*
Y81551D01*
G01X88425Y92000D02*
X86000D01*
G01X88500Y97260D02*
X88300Y97060D01*
Y92125D01*
X88425Y92000D01*
G01X91059Y104740D02*
X93520D01*
X94430Y103830D01*
G01D02*
X97260Y101000D01*
G01X91500Y109425D02*
X91059Y108984D01*
Y104740D01*
G01X81400Y95000D02*
X83660Y97260D01*
X85941D01*
G01X94650Y120941D02*
X90541D01*
X88900Y119300D01*
G01X100000Y119425D02*
X98574D01*
X97058Y120941D01*
X94650D01*
G01X88350Y123500D02*
X85950Y121100D01*
X82300D01*
G01X93312Y132925D02*
Y130813D01*
X88350Y125851D01*
Y123500D01*
G01X87500Y132925D02*
X80975D01*
X80400Y133500D01*
G01X93312Y132925D02*
X87500D01*
G01X96260Y408441D02*
X89169Y401350D01*
G01X88575Y450500D02*
X88500Y450575D01*
Y455260D01*
G01X88575Y450500D02*
X92575Y446500D01*
X100835D01*
G01X91593Y439000D02*
X93093Y437500D01*
X112222D01*
X117072Y442350D01*
X139350D01*
X144228Y447228D01*
X145425D01*
G01X91500Y434000D02*
X91571Y434071D01*
X91643Y434000D01*
X113672D01*
X118522Y438850D01*
X141547D01*
X145425Y442728D01*
G01X80650Y457650D02*
X83040Y455260D01*
X85941D01*
G01X91059Y462740D02*
X95000D01*
G01D02*
X97020D01*
X99760Y460000D01*
G01X91500Y467425D02*
X91059Y466984D01*
Y462740D01*
G01X98925Y478500D02*
X97769D01*
X93648Y482621D01*
G01X98925Y498500D02*
Y503500D01*
G01Y488500D02*
Y493500D01*
G01X96502Y503337D02*
Y501930D01*
G01D02*
Y495923D01*
X98925Y493500D01*
G01X93648Y482621D02*
X92006Y484263D01*
X91344Y485860D01*
X89889Y493176D01*
Y499832D01*
G01X98925Y483425D02*
X94678Y487672D01*
X93477Y490571D01*
G01D02*
X92075Y493957D01*
Y500856D01*
X92901Y501682D01*
G01X95184Y493787D02*
X94122Y494849D01*
Y499711D01*
X94622Y500211D01*
G01X96770Y508000D02*
X98040Y506730D01*
G01D02*
X98925Y505845D01*
Y503500D01*
G01X93000Y525925D02*
X91340Y524265D01*
Y521590D01*
X90990Y521240D01*
G01D02*
X90552D01*
X89787Y520475D01*
G01X87500Y521736D02*
Y522800D01*
G01D02*
Y525925D01*
G01X84075Y520479D02*
Y522094D01*
X82000Y524169D01*
Y525925D01*
G01X80613Y521815D02*
Y522193D01*
X79293Y523513D01*
G01X94500Y512500D02*
X96275Y514275D01*
Y519750D01*
G01D02*
Y524775D01*
X98500Y527000D01*
X98925D01*
G01X93000Y533925D02*
X94000D01*
X95650Y532275D01*
Y527977D01*
X93598Y525925D01*
X93000D01*
G01X87500Y533925D02*
X88500D01*
X90150Y532275D01*
Y527977D01*
X88098Y525925D01*
X87500D01*
G01X84723Y532202D02*
Y528050D01*
X82598Y525925D01*
X82000D01*
G01Y533925D02*
X83000D01*
X84723Y532202D01*
G01X85000Y568075D02*
Y568892D01*
X89610Y580015D01*
G01X85000Y568075D02*
X86404D01*
X87607Y567088D01*
X87926Y565484D01*
Y560574D01*
X89434Y559066D01*
X90991D01*
X91000Y559075D01*
G01X80000D02*
Y564925D01*
G01X92194Y572807D02*
X91500Y572113D01*
Y569575D01*
X93000Y568075D01*
G01X95500Y559075D02*
Y565446D01*
X95108Y566392D01*
X93425Y568075D01*
X93000D01*
G01X85000Y564925D02*
Y562148D01*
G01X100505Y561919D02*
X102051D01*
X103500Y563368D01*
Y566500D01*
X101925Y568075D01*
X101000D01*
G01D02*
Y568869D01*
X98300Y571569D01*
X96000Y577120D01*
Y579950D01*
X96220Y580170D01*
Y587000D01*
G01X101000Y559075D02*
X100505Y559570D01*
Y561919D01*
G01X101000Y564925D02*
X100597D01*
X97000Y568522D01*
Y569153D01*
G01X90680Y561766D02*
X92344Y563430D01*
X92938Y564863D01*
X93000Y564925D01*
G01X80000Y568075D02*
Y569822D01*
X81442Y573302D01*
G01X89610Y580015D02*
X91102Y583618D01*
Y587000D01*
G01X79930Y579000D02*
X81000D01*
X85984Y583984D01*
Y587000D01*
G01X93661D02*
Y576349D01*
X92194Y572807D01*
G01X109000Y573500D02*
X104404Y575403D01*
X101339Y582803D01*
Y587000D01*
G01X99500Y578500D02*
X98780Y579220D01*
Y587000D01*
G01X99500Y578500D02*
X101569Y573506D01*
X107000Y568075D01*
X107500D01*
G01X81442Y573302D02*
X81832Y574244D01*
X86036Y580536D01*
X86211Y580958D01*
X88284Y583031D01*
Y583256D01*
X88543Y583363D01*
Y587000D01*
G01X80400Y621200D02*
X84638D01*
X91102Y614736D01*
Y610000D01*
G01X93661D02*
Y617361D01*
X87977Y623045D01*
G01X95732Y622114D02*
X96220Y621626D01*
Y610000D01*
G01X98780D02*
Y617000D01*
G01X98500Y628425D02*
X98780Y628145D01*
Y617000D01*
G01X98500Y631575D02*
X98000Y632075D01*
Y634000D01*
X99051Y635051D01*
G01X87000Y631575D02*
X87500Y632075D01*
Y634700D01*
G01X88300Y639800D02*
Y638099D01*
X91000Y635399D01*
Y631575D01*
G01X80800Y639925D02*
X81159Y639566D01*
Y631834D01*
X80900Y631575D01*
G01X87977Y623045D02*
X87000Y624022D01*
Y628425D01*
G01X84700Y639925D02*
Y629529D01*
X85804Y628425D01*
X87000D01*
G01X95732Y622114D02*
X91100Y626746D01*
Y628425D01*
G01D02*
X91000D01*
G01X92500Y639925D02*
X94500Y637925D01*
Y631500D01*
X91425Y628425D01*
X91100D01*
G01X98500Y639925D02*
X101500Y636925D01*
Y630163D01*
X99762Y628425D01*
X98500D01*
G01X103037Y624462D02*
X101339Y622764D01*
Y610000D01*
G01X91532Y663261D02*
X93286D01*
X93525Y663500D01*
X112425D01*
G01X95032Y660000D02*
X111925D01*
X112425Y659500D01*
G01Y671500D02*
X101284D01*
G01X112425Y675500D02*
X101309D01*
G01X80425Y676000D02*
Y672000D01*
G01Y684000D02*
Y680000D01*
G01X112425Y679500D02*
X109500D01*
X92093Y696907D01*
Y723551D01*
X85500Y730144D01*
Y734450D01*
X79975Y739975D01*
G01X80425Y692000D02*
Y688000D01*
G01Y696000D02*
Y700000D01*
G01X101124Y715876D02*
X102000Y716752D01*
Y725000D01*
X105305Y728305D01*
X122583D01*
X128278Y734000D01*
X159000D01*
X163000Y730000D01*
X187041D01*
G01X102075Y711000D02*
Y714925D01*
X101124Y715876D01*
G01X98575Y731000D02*
X106425D01*
G01Y745000D02*
X98575D01*
G01X106425Y738000D02*
X98575D01*
G01X95760Y778559D02*
Y780315D01*
X90075Y786000D01*
Y790598D01*
X88023Y792650D01*
X85650D01*
X82000Y789000D01*
X81500D01*
G01X95980Y805970D02*
X99492D01*
X111850Y793612D01*
Y787149D01*
X113574Y785425D01*
X114500D01*
G01X91500Y830425D02*
X91059Y829984D01*
Y825740D01*
G01X94000D02*
X91059D01*
G01X97760Y822000D02*
Y824640D01*
X96660Y825740D01*
X94000D01*
G01X88500Y818260D02*
X88400Y818160D01*
Y813675D01*
X88500Y813575D01*
G01D02*
X95920D01*
G01D02*
X99383D01*
X119000Y793958D01*
Y788500D01*
X121841Y785659D01*
Y775967D01*
G01X118711Y797500D02*
X97711Y818500D01*
X94000D01*
G01X101500Y824271D02*
Y818496D01*
X121700Y798296D01*
Y790047D01*
X124317Y787430D01*
Y775367D01*
X121461Y772511D01*
Y763289D01*
X119836Y761664D01*
G01X80500Y822500D02*
X83542D01*
X85941Y820101D01*
Y818260D01*
G01X87150Y845941D02*
X92484D01*
X92500Y845925D01*
G01D02*
X96925D01*
X99000Y848000D01*
G01X79600Y858500D02*
Y852900D01*
X80850Y851650D01*
Y848500D01*
G01X97760Y1136941D02*
X84319Y1123500D01*
X82000D01*
G01X97760Y1142059D02*
X88319Y1151500D01*
X80000D01*
G01X97760Y1193780D02*
X91855D01*
X91500Y1193425D01*
G01X97760Y1185000D02*
Y1193780D01*
G01X91059Y1188740D02*
Y1192984D01*
X91500Y1193425D01*
G01X88500Y1176575D02*
X86000D01*
G01X88500Y1181260D02*
X88400Y1181160D01*
Y1176675D01*
X88500Y1176575D01*
G01X79991Y1181260D02*
X85941D01*
G01X106500Y53125D02*
X102500D01*
G01X118475Y83500D02*
X116075D01*
G01D02*
X116200Y83375D01*
Y78940D01*
X116000Y78740D01*
G01X129925Y65000D02*
X128775Y63850D01*
X118649D01*
X115743Y66756D01*
Y75475D01*
X115918Y75650D01*
G01X106740Y74000D02*
Y69260D01*
X110500Y65500D01*
X112500D01*
G01D02*
X113441Y66441D01*
Y71260D01*
G01X104509Y81551D02*
Y80360D01*
X106740Y78129D01*
Y74000D01*
G01X104740Y98441D02*
X127334D01*
X131193Y102300D01*
X135700D01*
G01X104740Y103559D02*
X109325D01*
X110425Y104659D01*
Y114000D01*
G01X145925Y126842D02*
Y127575D01*
X143000Y130500D01*
X131620D01*
X126120Y125000D01*
X121425D01*
X110425Y114000D01*
G01X122500Y110900D02*
X129400D01*
X131075Y112575D01*
Y114000D01*
G01X127925D02*
X125000D01*
X123500Y115500D01*
G01X114650Y131500D02*
Y138640D01*
X115680Y139670D01*
G01X114650Y131500D02*
X117500Y128650D01*
Y124328D01*
X114172Y121000D01*
X110400D01*
G01X103000Y133075D02*
Y136500D01*
G01X108350Y134059D02*
X103984D01*
X103000Y133075D01*
G01X122100Y139000D02*
X120425Y140675D01*
Y144500D01*
G01D02*
X115680Y139755D01*
Y139670D01*
G01X118500Y403500D02*
X129197D01*
X129425Y403728D01*
G01X112441Y408260D02*
X107966D01*
G01D02*
X106480D01*
X103740Y411000D01*
G01X109500Y403575D02*
X112441Y406516D01*
Y408260D01*
G01X110000Y392500D02*
X115075Y387425D01*
X148500D01*
G01X115000Y415740D02*
X115100Y415840D01*
Y420325D01*
X115000Y420425D01*
G01X117559Y415740D02*
X119740D01*
X122100Y418100D01*
G01X107240Y457441D02*
X118681Y446000D01*
X127000D01*
G01X122500Y473500D02*
X124775Y475775D01*
X139625D01*
X144672Y470728D01*
X145925D01*
G01X107240Y462559D02*
X118381Y473700D01*
X122300D01*
X122500Y473500D01*
G01X102075Y478500D02*
X104500D01*
G01X124500Y490575D02*
X125098D01*
X127150Y488523D01*
Y484225D01*
X124500Y481575D01*
G01Y490575D02*
X122070Y493005D01*
Y495240D01*
G01X113500Y490575D02*
X114098D01*
X116150Y488523D01*
Y484225D01*
X113500Y481575D01*
G01X114913Y495488D02*
X116925Y497500D01*
X117000D01*
G01X113500Y490575D02*
Y494075D01*
X114913Y495488D01*
G01X119000Y490575D02*
X119598D01*
X121650Y488523D01*
Y484225D01*
X119000Y481575D01*
G01Y490575D02*
X118490Y491085D01*
Y495330D01*
G01D02*
X119206Y496046D01*
X119454D01*
G01X102075Y483425D02*
X104500D01*
G01X124700Y495800D02*
X125250Y495250D01*
Y494751D01*
X126070Y493931D01*
G01X112070Y499790D02*
Y497570D01*
X109000Y494500D01*
Y490575D01*
G01X112070Y499790D02*
Y503570D01*
X112500Y504000D01*
G01X109000Y481575D02*
Y485000D01*
G01D02*
Y487425D01*
G01X102075Y517500D02*
Y521500D01*
G01X110000Y508500D02*
X107020D01*
X106740Y508780D01*
G01D02*
X106608D01*
X105417Y509971D01*
Y514074D01*
X102075Y517416D01*
Y517500D01*
G01X106500Y503575D02*
X102075Y508000D01*
Y509500D01*
G01X111000Y506000D02*
X109009D01*
X106584Y503575D01*
X106500D01*
G01X110000Y526490D02*
Y522955D01*
X112809Y516173D01*
G01X113000Y512104D02*
Y512450D01*
X109950Y515500D01*
X109604D01*
X107170Y517934D01*
Y519490D01*
X107320Y519640D01*
G01D02*
X106500Y520460D01*
Y528975D01*
X106000Y529475D01*
Y531425D01*
G01X108500Y512000D02*
X109500Y511000D01*
G01X135420Y537000D02*
X131500D01*
X121338Y526838D01*
Y523237D01*
G01X139890Y542000D02*
X132500D01*
X119038Y528538D01*
Y523237D01*
G01X142330Y532000D02*
X130138D01*
X123638Y525500D01*
Y523237D01*
G01X106000Y534575D02*
Y537500D01*
X108000Y539500D01*
G01X110000Y534575D02*
Y536525D01*
X110500Y537025D01*
Y542000D01*
X109000Y543500D01*
G01X110000Y531425D02*
Y526490D01*
G01X102075Y527000D02*
Y531500D01*
G01D02*
Y534000D01*
G01X115788Y573787D02*
X118704D01*
X124416Y568075D01*
G01D02*
X124500D01*
G01Y558075D02*
Y559499D01*
X121500Y562499D01*
Y566000D01*
X123575Y568075D01*
X124416D01*
G01X109000Y573500D02*
X112213Y570287D01*
X114338D01*
X114339Y570286D01*
X116113D01*
X117000Y569399D01*
Y568075D01*
G01D02*
X116597D01*
X114500Y565978D01*
Y559075D01*
G01X107500D02*
X108798D01*
X111000Y561277D01*
Y565501D01*
X108426Y568075D01*
X107500D01*
G01X125000Y562500D02*
Y564425D01*
X124500Y564925D01*
G01X106977Y561919D02*
Y562577D01*
X107500Y563100D01*
Y564925D01*
G01X121500Y557500D02*
X118000Y561000D01*
Y563925D01*
X117000Y564925D01*
G01X115788Y573787D02*
X115075Y574500D01*
X106411Y578089D01*
X106061Y578439D01*
X103898Y583658D01*
Y587000D01*
G01X123603Y575972D02*
X131500Y568075D01*
G01X123603Y575972D02*
X121575Y578000D01*
X113914D01*
X108939Y580061D01*
X107354Y581646D01*
X106457Y583811D01*
Y587000D01*
G01X135500Y568075D02*
Y569999D01*
X123999Y581500D01*
X120000D01*
G01D02*
X112706D01*
X110647Y582353D01*
X109016Y583984D01*
Y587000D01*
G01X106457Y610000D02*
Y615456D01*
X113001Y622000D01*
X115500D01*
G01X124323Y621748D02*
X120075Y617500D01*
X113000D01*
X109016Y613516D01*
Y610000D01*
G01X131875Y623376D02*
X122499Y614000D01*
X114450D01*
X111575Y611125D01*
Y610000D01*
G01X103898D02*
Y617896D01*
X107000Y621000D01*
G01X108601Y627084D02*
X113092Y631575D01*
X114000D01*
G01X118079Y639954D02*
Y637871D01*
X120033Y635917D01*
X121000Y633583D01*
Y631575D01*
G01X105000D02*
Y633500D01*
X106000Y634500D01*
G01X121000Y628425D02*
Y626375D01*
X116625Y622000D01*
X115500D01*
G01X121000Y639925D02*
X124500Y636425D01*
Y630125D01*
X124000Y629625D01*
Y629525D01*
X122900Y628425D01*
X121000D01*
G01X131000D02*
X124323Y621748D01*
G01X103037Y624462D02*
X105000Y626425D01*
Y628425D01*
G01D02*
X105742D01*
X109500Y632183D01*
Y635500D01*
X107000Y638000D01*
Y639925D01*
G01X114000D02*
Y636621D01*
X116680Y633941D01*
Y629526D01*
X115579Y628425D01*
X114000D01*
G01D02*
Y628003D01*
X107000Y621000D01*
G01X131500Y666543D02*
X125942D01*
X123608Y664209D01*
G01D02*
X122899Y663500D01*
X115575D01*
G01X131500Y663984D02*
X128483D01*
X124499Y660000D01*
G01D02*
X116075D01*
X115575Y659500D01*
G01X124830Y679870D02*
X122629D01*
X118999Y683500D01*
X115575D01*
G01X131500Y671661D02*
X128912D01*
X128671Y671420D01*
X121000D01*
X120400Y670820D01*
G01D02*
X119720Y671500D01*
X115575D01*
G01X124820Y674220D02*
X118805D01*
X117525Y675500D01*
X115575D01*
G01X120305Y677055D02*
X120360Y677000D01*
X128580D01*
X128800Y676780D01*
X131500D01*
G01X115575Y679500D02*
X117860D01*
X120305Y677055D01*
G01X115575Y687500D02*
X118800D01*
X121920Y684380D01*
G01D02*
X122651Y683649D01*
X126319Y682130D01*
X128670D01*
X128902Y681898D01*
X131500D01*
G01Y669102D02*
X123401D01*
G01D02*
X121799Y667500D01*
X115575D01*
G01X102075Y706500D02*
X106425D01*
G01X194000Y550000D02*
Y645001D01*
X190501Y648500D01*
X170782D01*
X154938Y655062D01*
X148815Y661185D01*
Y693185D01*
X141450Y700550D01*
X121940D01*
X119890Y698500D01*
X108703D01*
X106425Y700778D01*
Y706500D01*
G01X115575Y693000D02*
X117499D01*
X120550Y689949D01*
Y689650D01*
G01D02*
X122090D01*
X127283Y684457D01*
X131500D01*
G01X126185Y688915D02*
X122425Y692675D01*
Y694500D01*
G01X131000Y709882D02*
X124882D01*
X123025Y708025D01*
Y705000D01*
X122025Y704000D01*
X121075D01*
G01X109575Y706500D02*
Y703328D01*
X111553Y701350D01*
X112339D01*
G01X121075Y704000D02*
Y703402D01*
X119023Y701350D01*
X112339D01*
G01X112425Y693000D02*
Y695050D01*
X113375Y696000D01*
X118000D01*
G01X112425Y687500D02*
Y688800D01*
X113525Y689900D01*
X117500D01*
G01X190300Y725200D02*
X188000Y727500D01*
X162247D01*
X158047Y731700D01*
X129231D01*
X123536Y726005D01*
X111305D01*
X106425Y721125D01*
Y718000D01*
G01Y711000D02*
X102075D01*
G01X109575Y731000D02*
X112575Y734000D01*
X119000D01*
G01D02*
X121075Y731925D01*
Y731000D01*
G01D02*
X122025D01*
X123025Y732000D01*
Y735025D01*
X128882Y740882D01*
X131500D01*
G01X109575Y718000D02*
X114707Y723132D01*
X119975D01*
G01D02*
X121075Y722032D01*
Y718000D01*
G01D02*
X125499D01*
X127617Y720118D01*
X131000D01*
G01X125075Y715000D02*
X121075Y711000D01*
G01D02*
Y711926D01*
X119651Y713350D01*
X111925D01*
X109575Y711000D01*
G01X125352Y749277D02*
X121075Y745000D01*
G01D02*
Y745289D01*
X117864Y748500D01*
X113999D01*
X110499Y745000D01*
X109575D01*
G01X121075Y738151D02*
X128924Y746000D01*
X131500D01*
G01X121075Y738000D02*
Y738151D01*
G01X109575Y738000D02*
X113075Y741500D01*
X114857D01*
G01D02*
X118000D01*
X121075Y738425D01*
Y738151D01*
G01Y752000D02*
X122752Y753677D01*
X131500D01*
G01X117925Y752000D02*
Y751782D01*
X120454Y749253D01*
X121536D01*
G01X111500Y768575D02*
X111941Y769016D01*
Y773260D01*
G01X103240Y776000D02*
X107361D01*
X107365Y776004D01*
G01D02*
X110109Y773260D01*
X111941D01*
G01X114500Y780740D02*
X114600Y780840D01*
Y785325D01*
X114500Y785425D01*
G01X127000Y797075D02*
X126075D01*
X124000Y795000D01*
Y791000D01*
X126128Y788872D01*
X132370D01*
G01X145425Y815114D02*
X143733D01*
X141308Y812689D01*
X138401D01*
X134370Y808658D01*
X121842D01*
X121500Y809000D01*
G01D02*
X115681D01*
X105240Y819441D01*
G01Y824559D02*
Y826739D01*
X117001Y838500D01*
X122000D01*
G01X128425Y824614D02*
X126614D01*
X123000Y821000D01*
Y813212D01*
X124912Y811300D01*
X133246D01*
G01X145925Y834114D02*
X140539Y839500D01*
X123000D01*
X122000Y838500D01*
G01X104500Y834500D02*
Y836500D01*
X115500Y847500D01*
X144680D01*
X148281Y843899D01*
Y838882D01*
G01X120500Y845000D02*
X143848D01*
X145600Y843248D01*
Y838100D01*
G01X161000Y857575D02*
X117500D01*
G01X115500Y1143740D02*
X115600Y1143840D01*
Y1148325D01*
X115500Y1148425D01*
G01X112500Y1131575D02*
X112941Y1132016D01*
Y1136260D01*
G01X109500Y1139500D02*
X112740Y1136260D01*
X112941D01*
G01X105240Y1139500D02*
X109500D01*
G01X118059Y1143740D02*
X120300Y1145981D01*
Y1148500D01*
G01X105240Y1187559D02*
X112281Y1194600D01*
G01D02*
X120131Y1202450D01*
X123000D01*
X125340Y1204790D01*
X138635D01*
X145925Y1197500D01*
G01X123000Y1173500D02*
X126718D01*
X128718Y1175500D01*
X136999D01*
X139999Y1178500D01*
X145425D01*
G01X105240Y1182441D02*
X114181Y1173500D01*
X123000D01*
G01X148500Y58173D02*
X146800Y59873D01*
Y64000D01*
G01X133075Y65000D02*
Y60175D01*
X132400Y59500D01*
G01D02*
X134200Y57700D01*
X138700D01*
G01D02*
X143125D01*
X143500Y58075D01*
G01X144500Y71425D02*
X147573D01*
X148673Y72525D01*
Y79842D01*
G01X144500Y85425D02*
X147572D01*
X148673Y86526D01*
Y94000D01*
G01X127000Y77500D02*
Y74575D01*
G01D02*
X127984Y75559D01*
X132350D01*
G01X138200Y64000D02*
X137200Y65000D01*
X133075D01*
G01X138575Y81000D02*
Y73075D01*
X138650Y73000D01*
G01D02*
X140225Y74575D01*
X142000D01*
G01D02*
X144500D01*
G01X145425Y107842D02*
X143460D01*
X139722Y104104D01*
X137504D01*
X135700Y102300D01*
G01X132350Y91559D02*
Y94273D01*
G01X127000Y88575D02*
X129984Y91559D01*
X132350D01*
G01X140075Y107842D02*
Y108153D01*
X137500Y110728D01*
X134173D01*
X131173Y107728D01*
G01X148575Y107842D02*
Y109200D01*
X147475Y110300D01*
X142533D01*
X140075Y107842D01*
G01X145425Y103342D02*
X142500D01*
G01X142000Y98842D02*
X145425D01*
G01X144500Y88575D02*
X139075D01*
X138650Y89000D01*
G01Y94000D02*
Y89000D01*
G01X138575Y97000D02*
X138650Y96925D01*
Y94000D01*
G01X141575Y126842D02*
X143917Y124500D01*
X146968D01*
X149075Y126607D01*
Y126842D01*
G01X133673Y124500D02*
X134173Y124000D01*
X139501D01*
X141575Y126074D01*
Y126842D01*
G01X144673Y112842D02*
Y116715D01*
X147300Y119342D01*
G01X156600Y114600D02*
X150300D01*
X148542Y112842D01*
X144673D01*
G01X135000Y120500D02*
X134338D01*
X131930Y118092D01*
X131167D01*
X131075Y118000D01*
G01X138700Y119342D02*
Y119400D01*
X137600Y120500D01*
X135000D01*
G01X131075Y118000D02*
Y114000D01*
G01X141890Y246451D02*
X141761D01*
X140550Y247662D01*
Y249660D01*
X138490Y251720D01*
X135063D01*
X133963Y252820D01*
Y255892D01*
G01X159430Y244830D02*
X146669D01*
X142925Y248574D01*
Y249000D01*
G01X136500Y261000D02*
X138228Y262728D01*
X142907D01*
G01X146057D02*
Y263653D01*
X144482Y265228D01*
Y265728D01*
G01X142400Y269800D02*
X143500Y270900D01*
X147100D01*
X149272Y268728D01*
X156407D01*
G01X139000Y253925D02*
X138740D01*
X136773Y255892D01*
X133963D01*
G01X139000Y257075D02*
X142850D01*
X142925Y257000D01*
G01X146075D02*
Y253000D01*
G01X152500Y249501D02*
Y250501D01*
X150001Y253000D01*
X146075D01*
G01X142925D02*
Y249000D01*
G01X152783Y277728D02*
X152283Y278228D01*
X147500D01*
G01X160000Y298500D02*
X159000Y299500D01*
X149000D01*
X146500Y297000D01*
Y291000D01*
X149075Y288425D01*
X154500D01*
G01Y410000D02*
X150072D01*
X147300Y407228D01*
G01X144673Y400728D02*
Y403672D01*
X147300Y406299D01*
Y407228D01*
G01X135245D02*
X138700D01*
G01X135245D02*
X133047D01*
X132575Y407700D01*
Y408000D01*
G01Y403728D02*
X132483Y403820D01*
Y407908D01*
X132575Y408000D01*
G01X132675Y399500D02*
X132575Y399600D01*
Y403728D01*
G01X148673Y413728D02*
Y421526D01*
X147124Y423075D01*
X144500D01*
G01X127500Y421575D02*
X129934D01*
X132450Y419059D01*
X132850D01*
G01D02*
Y421837D01*
G01X127575Y435000D02*
Y433600D01*
X128675Y432500D01*
X130500D01*
G01X144500Y419925D02*
X141075Y416500D01*
X139150D01*
G01X139575Y424500D02*
X139150Y424075D01*
Y420193D01*
G01D02*
Y416500D01*
G01X145000Y432925D02*
X142950D01*
X142525Y432500D01*
X139150D01*
G01X127575Y429000D02*
X129284Y427291D01*
X136791D01*
X139150Y429650D01*
G01D02*
Y432500D01*
G01X145425Y451728D02*
X143728D01*
X138000Y446000D01*
X127000D01*
G01X145000Y436075D02*
X147766Y438841D01*
X153824D01*
X155309Y437356D01*
Y435073D01*
G01X131173Y451614D02*
X133559Y454000D01*
X138114D01*
X140075Y452039D01*
G01D02*
Y451728D01*
G01X148575D02*
Y451963D01*
X146510Y454028D01*
X142064D01*
X140075Y452039D01*
G01X132850Y435059D02*
X132791Y435000D01*
X127575D01*
G01X140575Y470728D02*
Y470400D01*
X142547Y468428D01*
X147010D01*
X149075Y470493D01*
Y470728D01*
G01X140575D02*
Y471326D01*
X138901Y473000D01*
X133524D01*
X132350Y471826D01*
Y471405D01*
X131673Y470728D01*
G01X144673Y456728D02*
Y460373D01*
X147300Y463000D01*
G01X152600Y463612D02*
X150562D01*
X149950Y463000D01*
X147300D01*
G01X135000D02*
X138700D01*
G01X135000D02*
Y464400D01*
X133900Y465500D01*
X131575D01*
G01Y456728D02*
Y457325D01*
X130900Y458000D01*
Y461000D01*
G01D02*
Y464825D01*
X131575Y465500D01*
G01X128425D02*
Y467425D01*
X129000Y468000D01*
G01X135500Y490575D02*
X136098D01*
X138150Y488523D01*
Y484225D01*
X135500Y481575D01*
G01X129370Y495230D02*
X129100Y495500D01*
X128000D01*
G01X135500Y490575D02*
X133075Y493000D01*
X131600D01*
X129370Y495230D01*
G01X130000Y490575D02*
X130598D01*
X132650Y488523D01*
Y484225D01*
X130000Y481575D01*
G01X126070Y493931D02*
X129426Y490575D01*
X130000D01*
G01X130880Y497560D02*
X132940Y495500D01*
X135000D01*
X141500Y489000D01*
Y487500D01*
G01X136000Y498500D02*
X133236D01*
X131110Y500626D01*
G01X138532Y507500D02*
X147425Y498607D01*
Y497000D01*
G01X147350Y487000D02*
X146799D01*
X141829Y491970D01*
Y495911D01*
X141390Y496350D01*
G01D02*
Y497862D01*
X137133Y502119D01*
G01X137479Y505170D02*
X144324Y498325D01*
G01D02*
Y495101D01*
X147425Y492000D01*
G01Y502000D02*
X145193Y504232D01*
G01X150575Y512000D02*
Y513425D01*
X149500Y514500D01*
X145754D01*
X143754Y516500D01*
X141500D01*
G01X147425Y522000D02*
X146465Y522960D01*
X142060D01*
G01D02*
X130333D01*
X128858Y521485D01*
G01X135378Y511650D02*
X141851D01*
X144335Y509166D01*
G01X147425Y507000D02*
X146501D01*
X144335Y509166D01*
G01X133470Y527000D02*
X128499D01*
X125938Y524439D01*
Y523237D01*
G01X135574Y514191D02*
X138731D01*
X139020Y514480D01*
G01X147425Y512000D02*
X145001D01*
X142810Y514191D01*
X139309D01*
X139020Y514480D01*
G01X147425Y517000D02*
X145065Y519360D01*
X136560D01*
G01D02*
X130080D01*
G01X145193Y504232D02*
X139925Y509500D01*
G01X147425Y527000D02*
X133470D01*
G01X147425Y537000D02*
X135420D01*
G01X147350Y542000D02*
X139890D01*
G01X147425Y532000D02*
X142330D01*
G01X135500Y564925D02*
Y562500D01*
G01X131500Y558075D02*
X128500Y561075D01*
Y566875D01*
X129700Y568075D01*
X131500D01*
G01X135500Y558075D02*
X139060Y561635D01*
Y565470D01*
X136455Y568075D01*
X135500D01*
G01X133491Y560490D02*
X132000Y561981D01*
Y564425D01*
X131500Y564925D01*
G01X131000Y631575D02*
X131500Y632075D01*
Y634500D01*
G01X135000Y637500D02*
Y631575D01*
G01X126500Y639925D02*
X128000Y638425D01*
Y630190D01*
X129765Y628425D01*
X131000D01*
G01X135000D02*
Y626501D01*
X131875Y623376D01*
G01X138500Y639925D02*
Y629951D01*
X136975Y628425D01*
X135000D01*
G01X148000Y483000D02*
X165501D01*
X195115Y512614D01*
Y539884D01*
X183500Y551499D01*
Y626000D01*
X170200Y639300D01*
X164558D01*
X158126Y641960D01*
X148111D01*
X143398Y643912D01*
X141900Y645410D01*
G01X124830Y679870D02*
X125361Y679339D01*
X131500D01*
G01Y674220D02*
X124820D01*
G01X131500Y687016D02*
X128084D01*
X126185Y688915D01*
G01X139350Y694910D02*
Y691340D01*
X137585Y689575D01*
X131500D01*
G01X130425Y694500D02*
Y695435D01*
X131525Y696535D01*
X137725D01*
X139350Y694910D01*
G01X154000Y709882D02*
X138000D01*
X135441Y712441D01*
G01X125575Y694500D02*
X128000D01*
G01X133575D02*
Y692000D01*
G01X131000Y717559D02*
X135722D01*
G01D02*
X136500Y716781D01*
Y713500D01*
X135441Y712441D01*
G01X135722Y717559D02*
X136500Y718337D01*
Y721500D01*
X135323Y722677D01*
X131000D01*
G01X135441Y712441D02*
X131000D01*
G01X136500Y728500D02*
X132575D01*
G01D02*
Y728265D01*
X131000Y726690D01*
Y722677D01*
G01X125075Y715000D02*
X131000D01*
G01X128065Y725566D02*
Y727140D01*
X129425Y728500D01*
G01X131500Y751118D02*
X127193D01*
X125352Y749277D01*
G01X154500Y740882D02*
X137618D01*
X136500Y742000D01*
G01D02*
X135059Y743441D01*
X131500D01*
G01X136500Y742000D02*
Y747000D01*
X135059Y748441D01*
Y748559D01*
G01D02*
X136500Y750000D01*
Y752500D01*
X135323Y753677D01*
X131500D01*
G01Y748559D02*
X135059D01*
G01X152266Y773430D02*
X147116D01*
X146800Y773114D01*
G01X148173Y766500D02*
Y768750D01*
X146800Y770123D01*
Y773114D01*
G01X131575Y762000D02*
X135425D01*
G01X137900Y766500D02*
Y770500D01*
X138200Y770800D01*
Y773114D01*
G01X135425Y762000D02*
Y762425D01*
X137900Y764900D01*
Y766500D01*
G01X128425Y762000D02*
Y762100D01*
X125654Y764871D01*
Y772281D01*
G01X132350Y801059D02*
X128366Y797075D01*
X127000D01*
G01X128500Y786500D02*
X127000Y785000D01*
Y784075D01*
G01D02*
X129516D01*
X130700Y785259D01*
X133350D01*
G01X139650Y785905D02*
Y782700D01*
G01D02*
X140701D01*
X144501Y786500D01*
X144925D01*
G01X139075Y790800D02*
X139650Y790225D01*
Y785905D01*
G01X138650Y798500D02*
X139075Y798925D01*
Y801984D01*
G01X127000Y804575D02*
X127338D01*
X129072Y806309D01*
X135628D01*
X139075Y802862D01*
Y801984D01*
G01X144925Y796500D02*
X140650D01*
X138650Y798500D01*
G01X145000Y782575D02*
X149000D01*
G01X144673Y820114D02*
Y823987D01*
X147300Y826614D01*
G01X131575Y820114D02*
Y824614D01*
G01D02*
Y828789D01*
X131900Y829114D01*
G01X140075Y815114D02*
Y815425D01*
G01X131173Y815000D02*
X134173Y818000D01*
X137500D01*
X140075Y815425D01*
G01X148575Y815114D02*
Y815349D01*
X146760Y817164D01*
X146628D01*
X146378Y817414D01*
X141299D01*
X140075Y816190D01*
Y815425D01*
G01X138428Y806903D02*
X140347Y808822D01*
X142570D01*
X144362Y810614D01*
X145425D01*
G01Y806114D02*
X145117Y805806D01*
X142467Y804709D01*
X141088D01*
G01X140575Y834114D02*
X142204D01*
X144318Y832000D01*
X147196D01*
X149075Y833879D01*
Y834114D01*
G01X132173Y834500D02*
Y834600D01*
X134337Y836764D01*
X138350D01*
X140575Y834539D01*
Y834114D01*
G01X147300Y826614D02*
X147684Y826998D01*
X155800D01*
G01X138700Y826614D02*
X134800D01*
G01X131900Y829114D02*
X132300D01*
X134800Y826614D01*
G01X142000Y987575D02*
X144500D01*
X145925Y989000D01*
G01X144425Y980500D02*
Y983500D01*
X145925Y985000D01*
G01X154502Y971101D02*
X150399D01*
X144425Y977075D01*
Y980500D01*
G01X142000Y984425D02*
X141598D01*
X139553Y986470D01*
X136505D01*
G01X142000Y977500D02*
Y976360D01*
X140019Y974379D01*
X135954D01*
X134877Y975456D01*
Y979850D01*
X136505Y981478D01*
Y986470D01*
G01X146644Y1007363D02*
X148351D01*
X150139Y1005575D01*
X151708D01*
X152783Y1004500D01*
G01X147229Y1004299D02*
X149130Y1002398D01*
X154095D01*
X155933Y1004236D01*
Y1004500D01*
G01X142907Y992649D02*
X141649D01*
X139435Y990435D01*
Y989500D01*
G01X146057Y992649D02*
Y993574D01*
X144482Y995149D01*
Y995649D01*
G01X133000Y1128925D02*
Y1118150D01*
X132175Y1117325D01*
G01X124500Y1148575D02*
X127000D01*
G01D02*
X129684D01*
X129700Y1148559D01*
X132350D01*
G01X138700Y1135000D02*
Y1135100D01*
X135800Y1138000D01*
G01X133000Y1132075D02*
X129000D01*
G01X135800Y1138000D02*
X132900D01*
X132400Y1137500D01*
G01D02*
X133000Y1136900D01*
Y1132075D01*
G01X144673Y1128500D02*
Y1132273D01*
X147300Y1134900D01*
Y1135000D01*
G01X152600D02*
X147300D01*
G01X139075Y1154000D02*
X138650Y1153575D01*
Y1149500D01*
G01D02*
Y1146000D01*
G01X145425Y1146400D02*
X142400D01*
X142000Y1146000D01*
X138650D01*
G01X127000Y1162575D02*
X127100D01*
X129084Y1164559D01*
X132350D01*
G01X127000Y1166000D02*
Y1162575D01*
G01X142500Y1161500D02*
X143500Y1160500D01*
X145425D01*
G01X138650Y1162000D02*
Y1165500D01*
G01X139075Y1170000D02*
Y1168575D01*
X138650Y1168150D01*
Y1165500D01*
G01X145425Y1156000D02*
X142500D01*
X138650Y1159850D01*
Y1162000D01*
G01X148575Y1165000D02*
Y1166115D01*
X145425Y1169265D01*
Y1169500D01*
G01X138500Y1180425D02*
X138925Y1180850D01*
X146425D01*
X146443Y1180867D01*
X148575Y1178735D01*
Y1178500D01*
G01X131673D02*
X136575D01*
X138500Y1180425D01*
G01X126360Y1185947D02*
X126372D01*
X128425Y1188000D01*
G01X140575Y1197500D02*
Y1197172D01*
X142747Y1195000D01*
X146810D01*
X149075Y1197265D01*
Y1197500D01*
G01X147300Y1190000D02*
X147684Y1190384D01*
X152600D01*
G01X147300Y1190000D02*
Y1187199D01*
X148673Y1185826D01*
Y1183500D01*
G01X131575D02*
Y1188000D01*
G01X138700Y1190000D02*
Y1193700D01*
X137600Y1194800D01*
X136800D01*
G01X130900Y1192500D02*
X133200Y1194800D01*
X136800D01*
G01X130900Y1192500D02*
X131575Y1191825D01*
Y1188000D01*
G01X145425Y1174000D02*
X144500D01*
X142500Y1176000D01*
G01X131173Y1198000D02*
X132173D01*
X134323Y1200150D01*
X138350D01*
X140575Y1197925D01*
Y1197500D01*
G01X169291Y56732D02*
X159000Y67023D01*
Y74000D01*
X156950Y76050D01*
G01X157000Y52982D02*
X157202Y52780D01*
X173213D01*
X177165Y56732D01*
G01X157000Y52982D02*
X151809Y58173D01*
X148500D01*
G01X156950Y76050D02*
X153158Y79842D01*
X148673D01*
G01X169291Y64606D02*
X163000Y70897D01*
Y81501D01*
X156782Y87719D01*
G01X177165Y80354D02*
X173072Y84447D01*
X165553D01*
X157000Y93000D01*
G01X156782Y87719D02*
X150501Y94000D01*
X148673D01*
G01X169291Y103976D02*
X161400Y111867D01*
Y117300D01*
X154124Y124576D01*
G01X157000Y101000D02*
Y102100D01*
X155758Y103342D01*
X148575D01*
G01X169291Y88228D02*
X166743D01*
X157000Y97971D01*
Y101000D01*
G01X156600Y114600D02*
X158200Y113000D01*
Y109400D01*
X167600Y100000D01*
X173189D01*
X177165Y103976D01*
G01X148575Y107842D02*
X153200D01*
G01X177165Y96102D02*
X175801D01*
X171899Y92200D01*
X167769D01*
X160900Y99069D01*
Y103447D01*
X156505Y107842D01*
X153200D01*
G01X157000Y93000D02*
X151158Y98842D01*
X148575D01*
G01X154124Y124576D02*
X151858Y126842D01*
X149075D01*
G01X165014Y268287D02*
X163913D01*
X163472Y268728D01*
X159557D01*
G01X162075Y288000D02*
X161128Y287053D01*
Y283003D01*
G01X167000Y288425D02*
X163843Y285268D01*
Y284058D01*
X162788Y283003D01*
X161128D01*
G01X154500Y291575D02*
X158500D01*
X158925Y292000D01*
G01X149500Y295500D02*
Y294999D01*
X152924Y291575D01*
X154500D01*
G01Y288425D02*
X158500D01*
X158925Y288000D01*
G01X167000Y291575D02*
X170358Y294933D01*
Y298858D01*
G01X169433Y283728D02*
Y286153D01*
X169358Y286228D01*
G01X166283Y283728D02*
Y282803D01*
X167858Y281228D01*
Y279310D01*
G01X160777Y275688D02*
X157973D01*
X155933Y277728D01*
G01X172400Y389000D02*
Y388400D01*
X169150Y385150D01*
X163865D01*
X160150Y388865D01*
Y389000D01*
G01X154500Y410000D02*
X160710Y416210D01*
X173257D01*
X177165Y420118D01*
G01X153850Y391559D02*
X149716Y387425D01*
X148500D01*
G01X155598Y426934D02*
X149739D01*
X148673Y428000D01*
G01X169291Y427992D02*
X164107D01*
X163049Y426934D01*
X155598D01*
G01X148673Y428000D02*
X149500Y428827D01*
Y432925D01*
X151648Y435073D01*
X155309D01*
G01X155686Y418730D02*
X157074Y420118D01*
X169291D01*
G01X148673Y413728D02*
X150684D01*
X155686Y418730D01*
G01X169291Y451614D02*
X155690D01*
X153324Y449248D01*
G01X148575Y447228D02*
X151304D01*
X153324Y449248D01*
G01X157000Y455738D02*
X152585D01*
X148575Y451728D01*
G01X177165Y459488D02*
X175909D01*
X171981Y455560D01*
X157178D01*
X157000Y455738D01*
G01Y442728D02*
X160728D01*
X165695Y447695D01*
X173210D01*
X177165Y443740D01*
G01X157000Y442728D02*
X148575D01*
G01X157000Y468500D02*
X166098D01*
X168154Y468499D01*
X169291Y467362D01*
G01X149075Y470728D02*
X151303Y468500D01*
X157000D01*
G01X177165Y467362D02*
X173415Y463612D01*
X152600D01*
G01X150575Y492000D02*
Y494500D01*
G01Y497000D02*
Y499500D01*
G01X150500Y487000D02*
Y489500D01*
G01X150575Y502000D02*
Y504500D01*
G01X173984Y509929D02*
Y504984D01*
X171000Y502000D01*
X166630D01*
G01D02*
X153725D01*
G01X175953Y509929D02*
Y503453D01*
X169500Y497000D01*
X159680D01*
G01D02*
X153725D01*
G01Y492000D02*
X165300D01*
G01D02*
X167747D01*
X177921Y502174D01*
Y509929D01*
G01X153650Y487000D02*
X159830D01*
G01D02*
X166000D01*
X181071Y502071D01*
Y513079D01*
G01X150575Y522000D02*
Y524500D01*
G01X170000Y504500D02*
X172016Y506516D01*
Y509929D01*
G01X150575Y517000D02*
Y519500D01*
G01Y507000D02*
Y509500D01*
G01X164929Y522921D02*
Y528681D01*
X161510Y532100D01*
Y537740D01*
X159730Y539520D01*
G01X164929Y520953D02*
X163047D01*
X161880Y522120D01*
Y527121D01*
X158790Y530211D01*
Y533400D01*
G01X153725Y532000D02*
Y530776D01*
X158870Y525631D01*
Y525510D01*
G01D02*
Y522630D01*
X162516Y518984D01*
X164929D01*
G01X153725Y527000D02*
Y524500D01*
G01X164929Y517016D02*
X161372D01*
X159508Y518880D01*
X159013D01*
X156025Y521868D01*
Y523085D01*
X154610Y524500D01*
X153725D01*
G01X158410Y516230D02*
X159593Y515047D01*
X164929D01*
G01X153725Y522000D02*
Y520915D01*
X158410Y516230D01*
G01X164929Y513079D02*
X157646D01*
X156345Y514380D01*
X153845D01*
X153725Y514500D01*
G01D02*
Y517000D01*
G01X168079Y509929D02*
X158570D01*
G01X153725Y512000D02*
X155796Y509929D01*
X158570D01*
G01X170047D02*
Y507600D01*
X168947Y506500D01*
X163240D01*
X162220Y505480D01*
G01X153725Y507000D02*
X156501D01*
X158021Y505480D01*
X162220D01*
G01X150500Y542000D02*
Y544500D01*
G01X150575Y537000D02*
Y539500D01*
G01Y527000D02*
Y529500D01*
G01Y532000D02*
Y534500D01*
G01X153650Y542000D02*
X156130Y539520D01*
X159730D01*
G01X153725Y537000D02*
X155941D01*
X158790Y534151D01*
Y533400D01*
G01X166500Y538925D02*
X163850Y536275D01*
Y533977D01*
X165902Y531925D01*
X166500D01*
G01D02*
Y530370D01*
X167190Y529680D01*
Y529510D01*
G01D02*
X168079Y528621D01*
Y526071D01*
G01X170047D02*
Y530472D01*
X171500Y531925D01*
G01X154500Y661425D02*
X160100D01*
X164152Y657373D01*
G01X169925Y651600D02*
Y651500D01*
G01X164152Y657373D02*
X169925Y651600D01*
G01X180925Y652000D02*
Y652100D01*
X178475Y654550D01*
X172049D01*
X169925Y652426D01*
Y651600D01*
G01X171977Y656850D02*
X169925Y658902D01*
Y659500D01*
G01D02*
X167141D01*
X162657Y663984D01*
X154500D01*
G01X166547Y663500D02*
X169925D01*
G01X166547D02*
X163504Y666543D01*
X154500D01*
G01X169925Y663500D02*
Y663735D01*
X172190Y666000D01*
X178525D01*
X180925Y663600D01*
Y663500D01*
G01X154500Y676780D02*
X160559D01*
X162012Y678233D01*
X165103D01*
G01X169925Y680500D02*
X167658Y678233D01*
X165103D01*
G01X154500Y671661D02*
X159051D01*
G01X169925Y672500D02*
X169086Y671661D01*
X166864D01*
X165875Y672650D01*
X163242D01*
X162253Y671661D01*
X159051D01*
G01X167060Y692500D02*
X166058D01*
X158015Y684457D01*
X154500D01*
G01Y687016D02*
X157264D01*
X161312Y691064D01*
Y696884D01*
G01X167679Y674254D02*
X169925Y676500D01*
G01X167679Y674254D02*
X166576Y675357D01*
X162422D01*
X161285Y674220D01*
X154500D01*
G01Y669102D02*
X164572D01*
G01X169925Y668500D02*
X166161D01*
X165559Y669102D01*
X164572D01*
G01X167642Y682217D02*
X169925Y684500D01*
G01X167642Y682217D02*
X162540D01*
X159662Y679339D01*
X154500D01*
G01X169925Y688500D02*
X167411Y685986D01*
X165032D01*
G01D02*
X162854D01*
X158766Y681898D01*
X154500D01*
G01X169925Y692500D02*
X167060D01*
G01X169925Y696500D02*
X169541Y696884D01*
X161312D01*
G01X171440Y708767D02*
X166267D01*
X163925Y706425D01*
Y706000D01*
G01D02*
X162602Y707323D01*
X154000D01*
G01X154500Y738323D02*
X158602D01*
X163925Y733000D01*
G01D02*
Y733425D01*
X166183Y735683D01*
X171586D01*
G01X171087Y724838D02*
X171053Y724872D01*
X168562D01*
X163925Y720235D01*
Y720000D01*
G01D02*
X163807Y720118D01*
X154000D01*
G01X171580Y716500D02*
X167190D01*
X163925Y713235D01*
Y713000D01*
G01D02*
X161925Y715000D01*
X154000D01*
G01X171500Y743500D02*
X167190D01*
X163925Y740235D01*
Y740000D01*
G01D02*
X157925Y746000D01*
X154500D01*
G01X172000Y751500D02*
X168190D01*
X163925Y747235D01*
Y747000D01*
G01D02*
X159807Y751118D01*
X154500D01*
G01X177165Y783504D02*
X182000Y778669D01*
Y773500D01*
X176500Y768000D01*
X157696D01*
X152266Y773430D01*
G01X148673Y791400D02*
X148075Y790802D01*
Y786500D01*
G01X148673Y791400D02*
Y791500D01*
G01X169291Y783504D02*
X160696D01*
X156500Y787700D01*
G01D02*
X152801D01*
X149101Y791400D01*
X148673D01*
G01X157000Y801500D02*
X148173D01*
G01X148075Y796500D02*
Y798550D01*
X148173Y798648D01*
Y801500D01*
G01X169291Y791378D02*
X164823D01*
X157000Y799201D01*
Y801500D01*
G01X169291Y815000D02*
X156499D01*
X154168Y812669D01*
G01D02*
X152113Y810614D01*
X148575D01*
G01X177165Y822874D02*
X173405Y819114D01*
X157000D01*
G01D02*
X152575D01*
X148575Y815114D01*
G01Y806114D02*
X153300D01*
G01D02*
X158267Y811081D01*
X173210D01*
X177165Y807126D01*
G01X149075Y834114D02*
X156900D01*
G01D02*
X165925D01*
X169291Y830748D01*
G01X155800Y826998D02*
X173415D01*
X177165Y830748D01*
G01X166850Y858559D02*
X165866Y857575D01*
X161000D01*
G01X159000Y972500D02*
X157601Y971101D01*
X154502D01*
G01X149075Y985000D02*
Y989000D01*
G01D02*
X152000D01*
X153500Y987500D01*
Y979250D01*
X152823Y978573D01*
G01X169433Y1010500D02*
Y1012925D01*
X169358Y1013000D01*
G01X164600Y998649D02*
X159557D01*
G01X166283Y1010500D02*
Y1009575D01*
X167858Y1008000D01*
Y1007500D01*
G01X164337Y1002475D02*
X159475D01*
X156407Y999407D01*
Y998649D01*
G01X172000Y1017425D02*
X168150D01*
X168075Y1017500D01*
G01X164925D02*
Y1021500D01*
G01X159500Y1023000D02*
Y1019500D01*
X161500Y1017500D01*
X164925D01*
G01X168075Y1021500D02*
Y1025500D01*
G01X153150Y1028430D02*
X166975D01*
X168075Y1027330D01*
Y1025500D01*
G01X152600Y1135000D02*
X160530Y1142930D01*
X173205D01*
X177165Y1146890D01*
G01X157000Y1146925D02*
X169256D01*
X169291Y1146890D01*
G01X157000Y1146925D02*
X154450D01*
X154025Y1146500D01*
X150625D01*
X150525Y1146400D01*
X148575D01*
G01D02*
Y1143848D01*
X148673Y1143750D01*
Y1141500D01*
G01X157000Y1155000D02*
X169055D01*
X169291Y1154764D01*
G01X148673Y1151000D02*
Y1153250D01*
X148575Y1153348D01*
Y1156000D01*
G01D02*
X153450D01*
X154450Y1155000D01*
X157000D01*
G01X148575Y1160500D02*
X153000D01*
X157000Y1164500D01*
G01X164000Y1171500D02*
X157000Y1164500D01*
G01X177165Y1178386D02*
X173279Y1174500D01*
X166200D01*
G01X148575Y1178500D02*
X152575Y1182500D01*
X157000D01*
G01D02*
X173405D01*
X177165Y1186260D01*
G01X157500Y1197500D02*
X165925D01*
X169291Y1194134D01*
G01X152600Y1190384D02*
X173415D01*
X177165Y1194134D01*
G01X169291Y1178386D02*
X157687D01*
X155286Y1175985D01*
G01D02*
X153301Y1174000D01*
X148575D01*
G01X149075Y1197500D02*
X157500D01*
G01X190425Y124500D02*
X185700D01*
G01D02*
X181075D01*
G01X186100Y392000D02*
Y395560D01*
X183610Y398050D01*
G01X172400Y389000D02*
X173975Y390575D01*
X179000D01*
G01D02*
Y396480D01*
X180570Y398050D01*
X183610D01*
G01X177500Y490075D02*
X181500D01*
G01X191575Y526500D02*
Y524000D01*
G01X181071Y522921D02*
X184080D01*
X186001Y521000D01*
X188425D01*
G01D02*
X188516Y520909D01*
Y518310D01*
G01D02*
Y516091D01*
X188425Y516000D01*
Y515500D01*
G01X173984Y528984D02*
Y526071D01*
G01X191575Y532000D02*
X191500Y531925D01*
Y529500D01*
G01X188425Y532000D02*
X186750D01*
X183660Y535090D01*
X182730D01*
G01D02*
X182320D01*
X181220Y533990D01*
Y530710D01*
X179785Y529275D01*
X177290D01*
X175953Y527938D01*
Y526071D01*
G01X177921D02*
X179971D01*
X183189Y529289D01*
X183720D01*
G01D02*
X185636D01*
X188425Y526500D01*
G01X176350Y540120D02*
X176190Y540280D01*
X173860D01*
X172505Y538925D01*
X171500D01*
G01X176350Y540120D02*
Y538475D01*
X174150Y536275D01*
Y533977D01*
X172098Y531925D01*
X171500D01*
G01X180925Y659500D02*
Y658500D01*
X179275Y656850D01*
X171977D01*
G01X173075Y684500D02*
X180500D01*
G01X173075Y680500D02*
X176500D01*
X177500Y679500D01*
G01X173075Y672500D02*
X175500D01*
G01X173075Y668500D02*
X175475D01*
G01X173075Y676500D02*
X179000D01*
G01X187925Y706000D02*
Y701000D01*
G01X179075Y706000D02*
X187925D01*
G01X175925D02*
X173158Y708767D01*
X171440D01*
G01X173075Y696500D02*
X181000D01*
G01X173075Y688500D02*
X178500D01*
X179000Y688000D01*
X182500D01*
G01X173075Y692500D02*
X174000D01*
X175500Y694000D01*
X179000D01*
G01X179075Y733000D02*
X184425D01*
G01D02*
Y738000D01*
G01X175925Y733000D02*
X173242Y735683D01*
X171586D01*
G01X171087Y724838D02*
X175925Y720000D01*
G01Y713000D02*
X172425Y716500D01*
X171580D01*
G01X175925Y740000D02*
X172425Y743500D01*
X171500D01*
G01X175925Y747000D02*
Y747575D01*
X172000Y751500D01*
G01X173150Y856000D02*
X175000D01*
X176575Y857575D01*
X179000D01*
G01X185000Y868100D02*
Y863500D01*
X185600Y862900D01*
Y860000D01*
G01X179000Y857575D02*
X181425Y860000D01*
X185600D01*
G01X177021Y1016322D02*
X178099D01*
X179200Y1017423D01*
Y1028856D01*
X178100Y1029956D01*
X172499D01*
X170929Y1028386D01*
Y1024429D01*
G01X172000Y1020575D02*
X172768D01*
X177021Y1016322D01*
G01X190559Y1235150D02*
Y1236440D01*
X189575Y1237424D01*
Y1240500D01*
G01D02*
X192000D01*
G01X178075Y1236500D02*
Y1230975D01*
X177000Y1229900D01*
G01D02*
X178050Y1228850D01*
X182600D01*
G01D02*
X188000D01*
G54D38*
X56243Y63842D03*
Y408878D03*
Y463878D03*
Y772264D03*
Y827264D03*
Y1136150D03*
Y1190650D03*
X64843Y63842D03*
X56743Y120342D03*
X65343D03*
X64843Y408878D03*
Y463878D03*
Y772264D03*
Y827264D03*
Y1136150D03*
Y1190650D03*
X146800Y64000D03*
X138200D03*
X147300Y119342D03*
X138700D03*
X147300Y407228D03*
X138700D03*
X147300Y463000D03*
X138700D03*
X146800Y773114D03*
X138200D03*
X147300Y826614D03*
X138700D03*
X147300Y1135000D03*
X138700D03*
X147300Y1190000D03*
X138700D03*
G54D29*
X25429Y511579D03*
Y513547D03*
Y515516D03*
Y517484D03*
Y519453D03*
Y521421D03*
X41571D03*
Y519453D03*
Y517484D03*
Y515516D03*
Y513547D03*
Y511579D03*
X164929Y513079D03*
Y522921D03*
Y520953D03*
Y518984D03*
Y517016D03*
Y515047D03*
X181071Y513079D03*
Y515047D03*
Y517016D03*
Y518984D03*
Y520953D03*
Y522921D03*
G54D47*
X56000Y1197327D03*
Y1200673D03*
X148500Y58173D03*
Y54827D03*
G54D57*
G01X33500Y694425D02*
X29000D01*
G01X47000Y722500D02*
X47075Y722575D01*
X52000D01*
G01D02*
X55376D01*
G01X82500Y605900D02*
X83425Y606825D01*
Y610000D01*
G01X114000Y591000D02*
X112975D01*
X111575Y589600D01*
Y587000D01*
G01X131500Y658975D02*
Y661425D01*
G01X126500Y706500D02*
X127323Y707323D01*
X131000D01*
G01X127983Y736234D02*
Y736518D01*
X129788Y738323D01*
X131500D01*
G01X156962Y692037D02*
X154500Y689575D01*
G01X154000Y722677D02*
X158177D01*
X159000Y723500D01*
Y725500D01*
G01X163925Y754000D02*
X163602Y753677D01*
X154500D01*
G54D39*
X55327Y97500D03*
Y113692D03*
X54827Y443728D03*
Y457228D03*
X55327Y778500D03*
X54827Y810000D03*
Y820614D03*
Y1173500D03*
Y1184000D03*
X71870Y56342D03*
X75216D03*
X71827Y75192D03*
X75173D03*
X58870Y70342D03*
X62216D03*
X58673Y97500D03*
X59370Y126842D03*
X62716D03*
X58673Y113692D03*
X71870Y401378D03*
X75216D03*
X58870Y415378D03*
X62216D03*
X71827Y420228D03*
X75173D03*
X58173Y443728D03*
Y457228D03*
X58870Y470378D03*
X62216D03*
X58673Y778500D03*
X71870Y764764D03*
X75216D03*
X71827Y783614D03*
X75173D03*
X58173Y810000D03*
Y820614D03*
X58870Y833764D03*
X62216D03*
X58870Y1142650D03*
X62216D03*
X71870Y1128650D03*
X75216D03*
X71827Y1147500D03*
X75173D03*
X58173Y1173500D03*
Y1184000D03*
X145327Y79842D03*
Y94000D03*
X131173Y107728D03*
X127827D03*
X144673Y112842D03*
X141327D03*
X133673Y124500D03*
X130327D03*
X144673Y400728D03*
X141327D03*
X145327Y428000D03*
Y413728D03*
X144673Y456728D03*
X141327D03*
X131173Y451614D03*
X127827D03*
X131673Y470728D03*
X128327D03*
X148173Y766500D03*
X144827D03*
X148173Y801500D03*
X144827D03*
X145327Y791500D03*
X144673Y820114D03*
X141327D03*
X131173Y815000D03*
X127827D03*
X132173Y834500D03*
X128827D03*
X145327Y1141500D03*
X144673Y1128500D03*
X141327D03*
X145327Y1151000D03*
Y1183500D03*
X131673Y1178500D03*
X128327D03*
X131173Y1198000D03*
X127827D03*
X148673Y79842D03*
Y94000D03*
Y428000D03*
Y413728D03*
Y791500D03*
Y1141500D03*
Y1151000D03*
Y1183500D03*
G54D48*
X82992Y17126D03*
X87992D03*
X92992D03*
X97992D03*
G54D58*
G01X91059Y455260D02*
Y452760D01*
G01X84050Y555925D02*
X91000D01*
G01X95500D02*
X101000D01*
G01D02*
X107500D01*
G01X91000D02*
X95500D01*
G01X114591Y556016D02*
X116884D01*
G01X117884Y555016D02*
X124409D01*
G01X111000Y555925D02*
X107500D01*
G01X132350Y80209D02*
X135500Y77059D01*
G01X143000Y564446D02*
Y566169D01*
X142242Y567999D01*
G54D49*
X99260Y71441D03*
Y76559D03*
X97260Y101000D03*
X96260Y408441D03*
Y413559D03*
X99760Y460000D03*
X95760Y773441D03*
Y778559D03*
X97760Y822000D03*
Y1136941D03*
Y1142059D03*
Y1185000D03*
X106740Y74000D03*
X104740Y103559D03*
Y98441D03*
X103740Y411000D03*
X107240Y462559D03*
Y457441D03*
X103240Y776000D03*
X105240Y824559D03*
Y819441D03*
Y1139500D03*
Y1187559D03*
Y1182441D03*
G54D59*
G01X14600Y379500D02*
X6000Y370900D01*
Y45500D01*
X7500Y44000D01*
G01X9425Y129000D02*
X14700Y134275D01*
Y137531D01*
G01X8900Y139356D02*
X10725Y137531D01*
X14700D01*
G01X13425Y393000D02*
X12000D01*
X9500Y390500D01*
Y384600D01*
X14600Y379500D01*
G01X13425Y719000D02*
X11300D01*
X9500Y717200D01*
Y711500D01*
X12000Y709000D01*
X13000D01*
G01X13425Y727000D02*
X6000D01*
G01X9425Y748000D02*
X6025D01*
G01X9425Y741000D02*
X6025D01*
G01X9425Y734000D02*
X6025D01*
G01X25075Y119000D02*
X14500Y108425D01*
Y76484D01*
X26378Y64606D01*
G01X9425Y124000D02*
Y129000D01*
G01X25075Y119000D02*
Y124000D01*
G01X14700Y137531D02*
X71569D01*
X71600Y137500D01*
G01X22425Y251500D02*
Y250378D01*
X24225Y248578D01*
X25545D01*
G01X12791Y261000D02*
Y264153D01*
G01X32716Y263728D02*
Y261716D01*
X32000Y261000D01*
G01X10000Y267303D02*
X12791D01*
G01X14600Y379500D02*
X18910Y375190D01*
X37190D01*
X43500Y381500D01*
X89845D01*
X90573Y380772D01*
X94346Y377000D01*
X102000D01*
G01X22300Y397500D02*
X23400Y396400D01*
Y383500D01*
G01X82500Y398000D02*
X76500Y392000D01*
X63000D01*
X57500Y397500D01*
X22300D01*
G01D02*
X11925Y407875D01*
Y487000D01*
G01X26378Y427992D02*
X15200Y439170D01*
Y470800D01*
X24880Y480480D01*
G01X13425Y502000D02*
X11000D01*
G01X10000Y496500D02*
Y492925D01*
X11925Y491000D01*
G01D02*
Y487000D01*
G01X27575D02*
Y483175D01*
X24880Y480480D01*
G01X13425Y511000D02*
X11000D01*
G01X10987Y523418D02*
X15302D01*
X16575Y522145D01*
Y520000D01*
G01X20375Y518875D02*
X19251Y520000D01*
X16575D01*
G01X13425D02*
X11000D01*
G01X13425Y515500D02*
X11000D01*
G01X13425Y506500D02*
X11000D01*
G01X27000Y534075D02*
X29500D01*
G01X23925Y641000D02*
Y645500D01*
G01X35260Y646000D02*
X32258D01*
G01X23925Y645500D02*
X22500D01*
X21000Y644000D01*
G01X23925Y660000D02*
X21525D01*
G01X23925Y654000D02*
X21525D01*
G01X23925Y666500D02*
X21525D01*
G01Y672500D02*
X23925D01*
G01Y683500D02*
X24075Y683350D01*
X31410D01*
X32760Y682000D01*
G01X23925Y683500D02*
Y686000D01*
G01Y680500D02*
Y683500D01*
G01Y672500D02*
Y673775D01*
X25500Y675350D01*
X37850D01*
X39000Y676500D01*
Y680500D01*
X37500Y682000D01*
G01X13425Y723000D02*
Y719000D01*
G01X30100Y735500D02*
X29500D01*
X26500Y732500D01*
G01X13425Y715000D02*
Y712500D01*
G01X19925Y734000D02*
X17500D01*
G01X19925Y741000D02*
X17500D01*
G01Y748000D02*
X19925D01*
G01X25075Y981500D02*
X25500Y981075D01*
Y977500D01*
G01X12791Y990925D02*
X11764D01*
X9838Y992851D01*
Y994729D01*
G01X32716Y990500D02*
Y992075D01*
X31791Y993000D01*
G01X12791Y994075D02*
X13850D01*
X15275Y995500D01*
G01X48200Y1160000D02*
X40701D01*
X39401Y1158700D01*
X37300D01*
G01X32000Y1215500D02*
X37200D01*
G01X32925Y1235500D02*
X27500Y1230075D01*
Y1229400D01*
G01X12941Y1234150D02*
X10241D01*
G01X13925Y1239500D02*
X11000D01*
G01X35866Y263728D02*
X38321D01*
X38880Y263169D01*
G01X43486Y282728D02*
X41031D01*
X40472Y283287D01*
G01X46636Y282728D02*
Y281153D01*
X47561Y280228D01*
G01X52575Y293000D02*
Y294300D01*
X54926Y296651D01*
G01X50150Y390559D02*
X54516D01*
X55500Y389575D01*
G01X37000Y390400D02*
X41470D01*
X41670Y390600D01*
X50109D01*
X50150Y390559D01*
G01X33000Y534075D02*
X35484D01*
G01X54075Y641000D02*
X56475D01*
G01X54075Y654000D02*
X56475D01*
G01X54075Y647000D02*
X56475D01*
G01X35260Y657000D02*
X32760D01*
G01X54075Y660000D02*
X56475D01*
G01X42740Y646000D02*
X45500D01*
G01X42740Y657000D02*
X45240D01*
G01X54075Y666500D02*
X56475D01*
G01X54075Y679000D02*
X56475D01*
G01X54075Y672500D02*
X56475D01*
G01X35260Y669500D02*
X32760D01*
G01X40800Y722500D02*
X33500Y715200D01*
Y699500D01*
X39000Y694000D01*
Y683500D01*
X37500Y682000D01*
G01D02*
X35260D01*
G01D02*
X32760D01*
G01X54075Y685000D02*
X56475D01*
G01X42740Y669500D02*
X45240D01*
G01X42740Y682000D02*
X45240D01*
G01X40800Y722500D02*
X47000D01*
G01X37575Y727500D02*
Y725725D01*
X40800Y722500D01*
G01X55376Y722575D02*
X61301Y728500D01*
X61500D01*
G01X70925Y751500D02*
X68125D01*
X67125Y750500D01*
X50900D01*
G01X53500Y801075D02*
X48000D01*
G01X38900Y800200D02*
X39725Y801025D01*
Y801075D01*
X48000D01*
G01X43986Y1009500D02*
X41531D01*
X40972Y1010059D01*
G01X35866Y990500D02*
X38321D01*
X38880Y989941D01*
G01X48005Y1012038D02*
X47136Y1011169D01*
Y1009500D01*
G01X56425Y1024000D02*
X55500D01*
X53000Y1021500D01*
G01X54925Y1160000D02*
X48200D01*
G01X37200Y1215500D02*
X55000D01*
X60500Y1210000D01*
Y1189500D01*
X62646Y1187354D01*
X65775D01*
X67575Y1185554D01*
Y1184000D01*
G01X162400Y1229900D02*
X55100D01*
X45500Y1239500D01*
X36027D01*
X32925Y1236398D01*
Y1235500D01*
G01X64543Y54767D02*
X64710D01*
X68508Y50969D01*
G01X78400Y47200D02*
Y50248D01*
X75216Y53432D01*
Y56342D01*
G01X80500Y74000D02*
Y65600D01*
X77900Y63000D01*
G01X62216Y70342D02*
Y67816D01*
X61300Y66900D01*
G01X66618Y75342D02*
X68342D01*
X69100Y76100D01*
G01X75173Y75192D02*
Y78000D01*
G01X76500Y70575D02*
X75173Y71902D01*
Y75192D01*
G01X68575Y81000D02*
Y98000D01*
G01X85500Y109425D02*
X82000D01*
X80150Y107575D01*
X77000D01*
G01X85941Y104740D02*
X83528D01*
X77000Y98212D01*
Y90075D01*
G01X58673Y97500D02*
X61500D01*
G01X71650Y91559D02*
Y94259D01*
G01Y108559D02*
Y111259D01*
G01X68575Y98000D02*
Y108425D01*
X61000Y116000D01*
Y121279D01*
X63163Y123442D01*
X64442D01*
X66500Y125500D01*
Y132400D01*
X71600Y137500D01*
G01X58673Y113692D02*
Y110927D01*
X58700Y110900D01*
G01X62716Y126842D02*
Y129542D01*
G01X75500Y130000D02*
Y127575D01*
G01D02*
X78425D01*
X79100Y126900D01*
X82300D01*
G01X85500Y112575D02*
X80074D01*
X78758Y111259D01*
X71650D01*
G01X76743Y119500D02*
Y116500D01*
G01X76000Y133500D02*
Y137500D01*
X80000Y141500D01*
X80400D01*
G01X72500Y283771D02*
X68029D01*
X66561Y282303D01*
G01X56730Y278169D02*
X65577D01*
X66561Y279153D01*
G01X66118Y401378D02*
X67322D01*
X68700Y400000D01*
G01X84500Y404000D02*
X80500D01*
X77878Y401378D01*
X75216D01*
G01X55500Y389575D02*
X60425D01*
X61000Y389000D01*
X78000D01*
X85000Y396000D01*
X111500D01*
G01X75075Y410000D02*
X78500D01*
G01X62216Y415378D02*
Y412678D01*
G01X66618Y420378D02*
X69018D01*
G01X75173Y420228D02*
X77773D01*
G01X78400Y415000D02*
X82000D01*
G01X68075Y427000D02*
X71000D01*
G01X77000Y435575D02*
X80657D01*
X88932Y427300D01*
X101200D01*
X104900Y423600D01*
Y420600D01*
X104800Y420500D01*
G01X80756Y465244D02*
X79800Y464288D01*
Y461043D01*
X77650Y458893D01*
Y457050D01*
X77000Y456400D01*
Y453075D01*
G01X85425Y450500D02*
X84025Y451900D01*
X81725D01*
X80642Y452983D01*
X77092D01*
X77000Y453075D01*
G01X58173Y443728D02*
X60773D01*
G01X74979Y437559D02*
X71650D01*
G01Y454059D02*
X68481Y457228D01*
X60773D01*
G01X70500Y443500D02*
X68075D01*
G01X58173Y457228D02*
X60773D01*
G01X62216Y470378D02*
X65250D01*
G01X74500Y475000D02*
X72075D01*
G01X71300Y460000D02*
X72000Y460700D01*
Y463100D01*
G01X71000Y529075D02*
X76500D01*
G01D02*
Y531476D01*
G01X71000Y537075D02*
X76500D01*
G01D02*
X82000D01*
G01X71000D02*
X68500D01*
G01X75000Y573425D02*
Y571968D01*
X73747Y570715D01*
G01X68000Y564925D02*
Y564700D01*
X70500Y562200D01*
X73500D01*
G01D02*
X75000Y563700D01*
Y564925D01*
G01X68000Y573425D02*
X75000D01*
G01X74000Y608425D02*
X78500D01*
G01D02*
Y607400D01*
X80000Y605900D01*
X82500D01*
G01X65552Y645503D02*
X63075Y643026D01*
Y641000D01*
G01Y655400D02*
Y660000D01*
G01Y655400D02*
X66400D01*
G01X63075Y647000D02*
X64055D01*
X65552Y645503D01*
G01X63075Y666500D02*
X65475D01*
G01X63075Y685000D02*
X65475D01*
G01X63075Y679000D02*
X65475D01*
G01X65500Y671500D02*
X64500Y672500D01*
X63075D01*
G01X74075Y704000D02*
X76500D01*
G01X74075Y709500D02*
X76500D01*
G01X61500Y728500D02*
X62221Y729221D01*
X70704D01*
X70925Y729000D01*
G01Y732000D02*
Y729000D01*
G01X74075Y715000D02*
X76475D01*
G01X74075Y729000D02*
Y732000D01*
G01Y742500D02*
X76475D01*
G01X70925Y749000D02*
Y751500D01*
G01X76500Y746500D02*
X74075D01*
G01D02*
Y751500D01*
G01X75216Y764764D02*
X77816D01*
G01X66118D02*
X68694D01*
G01X58673Y778500D02*
Y775800D01*
G01X63425Y778500D02*
X58673D01*
G01X77400Y775000D02*
Y778000D01*
G01X71500Y805500D02*
X75075D01*
X77000Y803575D01*
G01X66618Y783764D02*
X69018D01*
G01X68481Y800951D02*
X69589Y802059D01*
X71650D01*
G01X75173Y783614D02*
X76886D01*
X78000Y782500D01*
G01X57500Y797925D02*
X60000D01*
G01X88500Y810425D02*
X87403D01*
X78828Y819000D01*
X77000D01*
G01Y816575D02*
Y819000D01*
G01X58173Y820614D02*
X60773D01*
G01X71650Y818059D02*
Y821000D01*
G01X58173Y810000D02*
X61000D01*
G01X74575Y823500D02*
X77000D01*
G01X68075Y807500D02*
X68000Y807425D01*
Y804606D01*
G01X62216Y833764D02*
Y830875D01*
G01X77075Y834000D02*
X77018Y834057D01*
Y836764D01*
G01X76900Y828500D02*
X80000D01*
G01X75500Y852500D02*
Y849575D01*
G01X64400Y854500D02*
X73500D01*
X75500Y852500D01*
G01X73000Y1010500D02*
X68486D01*
X67061Y1009075D01*
G01Y1005925D02*
X64683D01*
X64108Y1006500D01*
G01X62216Y1142650D02*
Y1139950D01*
G01X75118Y1142650D02*
X77518D01*
G01X66118Y1128650D02*
X68543D01*
G01X75216D02*
X77816D01*
G01X66618Y1147650D02*
X69018D01*
G01X75173Y1147500D02*
X77773D01*
G01X76400Y1134000D02*
X79500D01*
G01X76500Y1160575D02*
Y1162975D01*
G01X71150Y1162559D02*
Y1165500D01*
G01X58173Y1173500D02*
X59173Y1172500D01*
X61000D01*
G01X58075Y1156000D02*
X66000D01*
X68150Y1158150D01*
Y1167425D01*
X67575Y1168000D01*
G01D02*
Y1173945D01*
X67850Y1174220D01*
Y1181000D01*
X67575Y1181275D01*
Y1184000D01*
G01X76500Y1176575D02*
X79106D01*
G01X58173Y1184000D02*
Y1181673D01*
X57500Y1181000D01*
G01X71150Y1178559D02*
X74313D01*
G01X76400Y1191000D02*
Y1188100D01*
G01X56000Y1200673D02*
Y1203273D01*
G01X65000Y1200075D02*
X73505D01*
G01D02*
X82000D01*
X85500Y1196575D01*
G01X91500Y56275D02*
Y59281D01*
X96682Y64463D01*
X101538D01*
X106500Y59501D01*
Y56275D01*
G01X91500Y112575D02*
X90075D01*
X86925Y109425D01*
X85500D01*
G01X91575Y92000D02*
X92667D01*
X94316Y93649D01*
G01X85500Y109425D02*
X85941Y108984D01*
Y104740D01*
G01D02*
Y103059D01*
X88802Y100198D01*
G01X94316Y93649D02*
Y98398D01*
X92516Y100198D01*
X88802D01*
G01X94316Y93649D02*
X103976D01*
X104127Y93800D01*
X112500D01*
X114725Y91575D01*
Y86500D01*
G01X91059Y97260D02*
Y94630D01*
G01X94650Y126059D02*
X99134D01*
X103000Y129925D01*
G01X104600Y121000D02*
X104100D01*
X102525Y122575D01*
X100000D01*
G01X80400Y141500D02*
Y216400D01*
X102000Y238000D01*
G01X87500Y136075D02*
X82075Y141500D01*
X80400D01*
G01X102000Y238000D02*
X124000Y216000D01*
Y150630D01*
G01X102000Y377000D02*
Y384500D01*
X107000Y389500D01*
G01Y400425D02*
X105875D01*
X100500Y405800D01*
Y418000D01*
X103000Y420500D01*
X104800D01*
G01X85941Y462740D02*
X90421Y458260D01*
X94260D01*
X107520Y445000D01*
X110500D01*
G01X109000Y478425D02*
X101150Y470575D01*
X91500D01*
G01X80756Y465244D02*
Y483256D01*
X84575Y487075D01*
G01X85500Y467425D02*
Y463181D01*
X85941Y462740D01*
G01X85500Y467425D02*
X82937D01*
X80756Y465244D01*
G01X85500Y467425D02*
X86425D01*
X89575Y470575D01*
X91500D01*
G01X85500D02*
Y472975D01*
G01X87500Y487075D02*
X84575D01*
G01X87500D02*
Y491000D01*
G01X86500Y481500D02*
X87500Y482500D01*
Y483925D01*
G01X98925Y515000D02*
Y517500D01*
G01Y512500D02*
Y509500D01*
G01Y521500D02*
Y524000D01*
G01Y531500D02*
Y534000D01*
G01X82000Y529075D02*
Y531476D01*
G01X87500Y529075D02*
Y531476D01*
G01X93000Y529075D02*
Y531476D01*
G01X82000Y537075D02*
X87500D01*
G01D02*
X93000D01*
G01X84050Y555925D02*
X80000D01*
G01X83300Y624100D02*
X80900Y626500D01*
Y628425D01*
G01X92500Y643075D02*
X84700D01*
G01X80800D02*
X84700D01*
G01X92500D02*
X98500D01*
G01D02*
X107000D01*
G01X131425Y656500D02*
X130925Y656000D01*
X90300D01*
X88500Y657800D01*
Y666500D01*
X90500Y668500D01*
G01X83575Y676000D02*
X86000D01*
G01X87443Y684000D02*
X89273Y685830D01*
Y690727D01*
X88000Y692000D01*
X83575D01*
G01X87443Y684000D02*
X86000D01*
G01X87443D02*
X92500Y678943D01*
Y670500D01*
X90500Y668500D01*
G01X83575Y684000D02*
X86000D01*
G01X90500Y668500D02*
X91500Y667500D01*
X112425D01*
G01X83575Y680000D02*
X86000D01*
G01D02*
X87200D01*
X89000Y678200D01*
Y673800D01*
X87200Y672000D01*
X83575D01*
G01Y700000D02*
X86000D01*
G01X83575Y688000D02*
X86000D01*
G01X83575Y715000D02*
Y709500D01*
G01D02*
Y704000D01*
G01X98925Y706500D02*
Y711000D01*
G01D02*
Y711083D01*
X97500Y712508D01*
Y728027D01*
X95425Y730102D01*
Y731000D01*
G01X83575Y696000D02*
X86000D01*
G01D02*
X86700D01*
X88500Y697800D01*
Y702500D01*
X87000Y704000D01*
X83575D01*
G01X95425Y731000D02*
X93000D01*
G01X95425Y738000D02*
X93025D01*
G01X95425Y745000D02*
X93000D01*
G01X88500Y810425D02*
X98785D01*
X114500Y794710D01*
Y788575D01*
G01X85500Y830425D02*
X85941Y829984D01*
Y825740D01*
G01X92950Y821707D02*
X92859D01*
X91059Y819907D01*
Y818260D01*
G01X85500Y830425D02*
X86593D01*
X89743Y833575D01*
X91500D01*
G01D02*
X94000D01*
X95575Y832000D01*
X106001D01*
X116351Y842350D01*
X142999D01*
G01X125500Y862700D02*
X118199D01*
X97499Y842000D01*
X86311D01*
X84000Y844311D01*
Y844950D01*
G01X87150Y851059D02*
X90516D01*
X92500Y849075D01*
G01X99000Y853000D02*
X95075Y849075D01*
X92500D01*
G01X85500Y833575D02*
X82000D01*
G01X87150Y851059D02*
X85400Y852809D01*
Y858500D01*
G01X88500Y1173425D02*
X91000D01*
G01X85500Y1193425D02*
X85941Y1192984D01*
Y1188740D01*
G01X85500Y1193425D02*
X86425D01*
X89575Y1196575D01*
X91500D01*
G01X85500Y1193425D02*
X81000D01*
G01X91059Y1181260D02*
Y1177581D01*
X94730Y1173910D01*
G01X116737Y1162763D02*
X101202Y1178298D01*
Y1202401D01*
X114078Y1215277D01*
X162800D01*
G01X123500Y59500D02*
X126600D01*
G01X107659Y81551D02*
X110976D01*
X112925Y83500D01*
G01X127000Y85425D02*
X124329D01*
X122529Y83625D01*
G01D02*
Y77617D01*
X118559Y73647D01*
Y71260D01*
G01X112925Y83500D02*
Y84700D01*
X114725Y86500D01*
G01X121925Y66500D02*
X120360D01*
X118559Y68301D01*
Y71260D01*
G01X127000Y71425D02*
X124925D01*
X122017Y68517D01*
Y66592D01*
X121925Y66500D01*
G01X114725Y86500D02*
X119654D01*
X122529Y83625D01*
G01X112500Y76000D02*
X113441Y76941D01*
Y78740D01*
G01X125075Y66500D02*
X126986Y68411D01*
X130320D01*
X132350Y70441D01*
G01X122500Y105100D02*
Y102000D01*
G01X123575Y144500D02*
X126500Y141575D01*
Y135400D01*
X122100Y131000D01*
G01X103000Y129925D02*
X107366D01*
X108350Y128941D01*
G01D02*
X112559D01*
X114500Y127000D01*
G01D02*
X112500Y125000D01*
X108800D01*
X104800Y121000D01*
X104600D01*
G01X124000Y150630D02*
Y144925D01*
X123575Y144500D01*
G01X102000Y238000D02*
Y377000D01*
G01X179000Y387425D02*
X174075Y382500D01*
X114500D01*
X107500Y389500D01*
X107000D01*
G01X117559Y411059D02*
Y408260D01*
G01X109500Y400425D02*
X107000D01*
G01X113500Y403575D02*
X114200D01*
X116000Y405375D01*
Y406701D01*
X117559Y408260D01*
G01X129425Y408000D02*
X125686D01*
X124378Y409308D01*
G01X113000Y394500D02*
X116925Y390575D01*
X148500D01*
G01X111500Y396000D02*
X113000Y394500D01*
G01X113500Y400425D02*
X111500Y398425D01*
Y396000D01*
G01X117500Y398500D02*
X125875D01*
X126875Y399500D01*
G01X127500Y418425D02*
Y417000D01*
X123317Y412817D01*
X119317D01*
X117559Y411059D01*
G01X124425Y435000D02*
X122313D01*
X115000Y427687D01*
Y423575D01*
G01X104800Y420500D02*
X106500D01*
X109000Y418000D01*
Y414300D01*
X110800Y412500D01*
X116118D01*
X117559Y411059D01*
G01X115000Y423575D02*
X121025D01*
X126175Y418425D01*
X127500D01*
G01X112441Y415740D02*
Y418434D01*
G01X136425Y424500D02*
X126500D01*
X124425Y426575D01*
Y429000D01*
G01X124500Y478425D02*
X130000D01*
G01X119000D02*
X124500D01*
G01X113500D02*
X119000D01*
G01X113500D02*
Y476000D01*
G01X125100Y461000D02*
X124000D01*
X122000Y463000D01*
G01X124500Y487425D02*
Y485000D01*
G01X119000Y487425D02*
Y485000D01*
G01X113500Y487425D02*
Y485000D01*
G01X106500Y500425D02*
X106925Y500000D01*
X109000D01*
G01X102075Y503500D02*
X105150Y500425D01*
X106500D01*
G01X102075Y493500D02*
X105760D01*
G01X105732Y496844D02*
X103731D01*
X102075Y498500D01*
G01Y488500D02*
X105815D01*
G01X116000Y523925D02*
X114425D01*
X113500Y523000D01*
G01X116000Y523925D02*
Y521000D01*
X118000Y519000D01*
G01X116000Y527075D02*
Y529500D01*
G01X114500Y555925D02*
X114591Y556016D01*
G01X116884D02*
X117884Y555016D01*
G01X124409D02*
X124500Y554925D01*
G01X114500Y555925D02*
X111000D01*
G01X124500Y554925D02*
X128500D01*
G01X126500Y643075D02*
X121000D01*
G01D02*
X114000D01*
G01D02*
X107000D01*
G01X117925Y704000D02*
Y704925D01*
X119500Y706500D01*
Y707500D01*
G01X117925Y711000D02*
Y710075D01*
X119500Y708500D01*
Y707500D01*
G01X117925Y718000D02*
Y717075D01*
X119500Y715500D01*
G01X117925Y731000D02*
X115525D01*
G01X117925Y745000D02*
X115525D01*
G01X117925Y738000D02*
X115525D01*
G01X112294Y754294D02*
Y760242D01*
X111500Y761036D01*
Y765425D01*
G01D02*
X113257D01*
X116407Y768575D01*
X117500D01*
G01D02*
X117059Y769016D01*
Y773260D01*
G01X117500Y765425D02*
Y763076D01*
X115563Y761139D01*
Y759063D01*
G01X107500Y782530D02*
X109241Y780789D01*
X109500D01*
Y780740D01*
X111941D01*
G01X126100Y829114D02*
X123000D01*
G01X102500Y979500D02*
X110500D01*
X125500Y964500D01*
Y862700D01*
G01X112500Y1128425D02*
X110000D01*
G01X121000Y1131575D02*
X118500D01*
G01D02*
X118059Y1132016D01*
Y1136260D01*
G01X118500Y1128425D02*
X121000D01*
G01X112941Y1143740D02*
Y1146240D01*
G01X126600Y1137500D02*
X123500D01*
G01X115500Y1151575D02*
X118000D01*
G01X135925Y1154000D02*
X125500D01*
X116737Y1162763D01*
G01X125100Y1192500D02*
X121500Y1188900D01*
Y1182500D01*
X123000Y1181000D01*
G01X148500Y54827D02*
X148402Y54925D01*
X143500D01*
G01X135014Y51400D02*
Y50977D01*
G01Y51400D02*
X136814Y53200D01*
X141775D01*
X143500Y54925D01*
G01X132350Y86441D02*
Y80209D01*
G01X135500Y77059D02*
Y70441D01*
G01X145327Y79842D02*
X142727D01*
G01X132350Y70441D02*
X135500D01*
G01X135425Y81000D02*
Y97000D01*
G01X142727Y94000D02*
X145327D01*
G01X136925Y107842D02*
X134525D01*
G01X127827Y107728D02*
Y105673D01*
X128500Y105000D01*
X132725D01*
X134525Y106800D01*
Y107842D01*
G01X135425Y97000D02*
X134500D01*
X132500Y99000D01*
G01X130327Y124500D02*
Y125434D01*
X132400Y127507D01*
X137760D01*
X138425Y126842D01*
G01X141327Y112842D02*
Y115542D01*
G01X127925Y118000D02*
X125500D01*
G01X130327Y124500D02*
Y122327D01*
X128016Y120016D01*
Y118091D01*
X127925Y118000D01*
G01X189054Y138631D02*
X186183Y135760D01*
X138760D01*
X135750Y132750D01*
G01X130900Y135000D02*
X133500D01*
X135750Y132750D01*
G01X130900Y135000D02*
X127500Y131600D01*
Y129500D01*
G01X136482Y264153D02*
X134761D01*
X133529Y265385D01*
G01X136482Y267303D02*
X138860D01*
X139435Y266728D01*
G01X149000Y250000D02*
X148000Y249000D01*
X146075D01*
G01X141327Y400728D02*
Y398000D01*
G01X157496Y400176D02*
X149676D01*
X144500Y395000D01*
X139300D01*
X138000Y396300D01*
Y402000D01*
X140128Y404128D01*
X140880D01*
X143000Y406248D01*
Y410199D01*
X141199Y412000D01*
X138870D01*
X136150Y414720D01*
Y424225D01*
X136425Y424500D01*
G01X132850Y429941D02*
X136000D01*
G01X145327Y428000D02*
X142727D01*
G01X132850Y413941D02*
X132246Y414545D01*
X129314D01*
G01X145327Y413728D02*
Y416500D01*
G01X127827Y451614D02*
Y450680D01*
X129507Y449000D01*
X136500D01*
X136925Y449425D01*
Y451728D01*
G01X135349Y468652D02*
Y468651D01*
X137500Y466500D01*
X140500D01*
X142000Y465000D01*
Y457401D01*
X141327Y456728D01*
G01X128425D02*
X128128D01*
X125200Y453800D01*
G01X127827Y451614D02*
X127386D01*
X125200Y453800D01*
G01X128327Y470728D02*
X126628D01*
X125500Y469600D01*
G01X137425Y470728D02*
X135349Y468652D01*
G01X130000Y478425D02*
X135500D01*
G01Y487425D02*
Y485024D01*
G01X130000Y487425D02*
Y485025D01*
G01X128500Y554925D02*
X131500D01*
G01X135500D02*
X139425D01*
X143000Y558500D01*
Y564446D01*
G01X142242Y567999D02*
X140110Y573146D01*
Y621564D01*
X142390Y627067D01*
Y640330D01*
X139645Y643075D01*
X138500D01*
G01X131500Y554925D02*
X135500D01*
G01X138500Y643075D02*
X126500D01*
G01X131425Y656500D02*
Y658900D01*
X131500Y658975D01*
G01X134575Y656500D02*
Y659000D01*
G01X152075Y729000D02*
Y727575D01*
X150000Y725500D01*
X143500D01*
X139150Y721150D01*
Y712500D01*
G01X148925Y729000D02*
X146000D01*
G01X151300Y756400D02*
X142599D01*
X138575Y760424D01*
Y762000D01*
G01X144827Y766500D02*
Y763510D01*
G01X129705Y777796D02*
X132050Y780141D01*
X133350D01*
G01X133900Y776000D02*
X132100Y774200D01*
Y766500D01*
G01X173800Y759446D02*
X144655D01*
X141523Y762578D01*
Y773924D01*
X145000Y777401D01*
Y779425D01*
G01X135925Y790800D02*
Y788576D01*
X136500Y788001D01*
Y780720D01*
X137795Y779425D01*
X145000D01*
G01X127000Y793925D02*
Y793000D01*
X128500Y791500D01*
G01X127000Y780925D02*
X128411D01*
X129285Y781799D01*
G01X132350Y795941D02*
Y793241D01*
G01X144827Y801500D02*
X143622Y800295D01*
X141993D01*
G01X145327Y791500D02*
X142727D01*
G01X127000Y801425D02*
X127936D01*
X130170Y803659D01*
X134530D01*
X135558Y802631D01*
Y791167D01*
X135925Y790800D01*
G01X128425Y820114D02*
X125500D01*
G01X127827Y815000D02*
X125227D01*
G01X141327Y820114D02*
Y822814D01*
G01X136925Y815114D02*
X134525D01*
G01X141327Y822814D02*
X141728Y823215D01*
Y828866D01*
X137425Y833169D01*
Y834114D01*
G01X128827Y834500D02*
X126000D01*
G01X179000Y854425D02*
X176788Y852213D01*
X171787D01*
X170000Y854000D01*
Y860189D01*
X168989Y861200D01*
X127000D01*
X125500Y862700D01*
G01X147575Y980500D02*
X150500D01*
X151000Y981000D01*
G01X136482Y994074D02*
X134761D01*
X133529Y995306D01*
G01X136482Y997224D02*
X138860D01*
X139435Y996649D01*
G01X127000Y1145425D02*
Y1143000D01*
G01X145327Y1141500D02*
X141649D01*
G01X141327Y1128500D02*
Y1130520D01*
X142088Y1131281D01*
G01X129000Y1128925D02*
X128925Y1129000D01*
X126500D01*
G01X132350Y1143441D02*
X135500D01*
G01X127000Y1159425D02*
Y1157025D01*
G01X132350Y1159441D02*
Y1156741D01*
G01X145327Y1151000D02*
X142727D01*
G01X135925Y1170000D02*
X135650Y1169725D01*
Y1154275D01*
X135925Y1154000D01*
G01Y1170000D02*
Y1171425D01*
X136930Y1172430D01*
X140571D01*
X142500Y1170501D01*
Y1166945D01*
X144445Y1165000D01*
X145425D01*
G01X128327Y1178500D02*
X127970D01*
X125440Y1175970D01*
G01X128425Y1183500D02*
Y1178598D01*
X128327Y1178500D01*
G01X145327Y1183500D02*
X142500D01*
G01D02*
X138575D01*
X138500Y1183575D01*
G01X137425Y1197500D02*
X135000D01*
G01X127827Y1198000D02*
X125000D01*
G01X159557Y263728D02*
X161105Y265276D01*
Y266081D01*
G01X156407Y263728D02*
Y265303D01*
X155482Y266228D01*
G01X152783Y282728D02*
X150328D01*
X149769Y283287D01*
G01X155933Y282728D02*
Y281153D01*
X156858Y280228D01*
G01X164296Y297723D02*
X162075Y295502D01*
Y292000D01*
G01X157150Y393200D02*
Y388000D01*
X155591Y386441D01*
X153850D01*
G01X148500Y390575D02*
Y393200D01*
X150300Y395000D01*
X155350D01*
X157150Y393200D01*
G01X166600Y389000D02*
Y391900D01*
X163500Y395000D01*
X158950D01*
X157150Y393200D01*
G01X184000Y403500D02*
X160820D01*
X157496Y400176D01*
G01X169000Y535075D02*
X166500D01*
G01X171500D02*
X169000D01*
G01X166500Y542075D02*
X169000D01*
G01D02*
X171500D01*
G01X167075Y706000D02*
X169475D01*
G01X167075Y733000D02*
X169475D01*
G01X167075Y713000D02*
X169475D01*
G01X167075Y720000D02*
X169475D01*
G01X159000Y725500D02*
Y725501D01*
X155501Y729000D01*
X152075D01*
G01X163925Y756500D02*
Y754000D01*
G01X167075Y747000D02*
X169475D01*
G01X167075Y740000D02*
X169475D01*
G01X167075Y754000D02*
Y756500D01*
G01X155800Y779425D02*
X149000D01*
G01X155800D02*
Y777200D01*
X162200Y770800D01*
X173200D01*
G01X166850Y853441D02*
X165866Y854425D01*
X161000D01*
G01X149500Y850500D02*
X150000D01*
X153925Y854425D01*
X161000D01*
G01X161581Y995673D02*
X159557Y993649D01*
G01X152783Y1009500D02*
X150328D01*
X149769Y1010059D01*
G01X161581Y995673D02*
X174974D01*
X178724Y999423D01*
Y1007756D01*
X178811Y1007843D01*
G01X155933Y1009500D02*
Y1007925D01*
X156858Y1007000D01*
G01X156407Y993649D02*
Y995224D01*
X155482Y996149D01*
G01X162500Y1023000D02*
Y1023075D01*
X164925Y1025500D01*
G01X166200Y1174500D02*
X160900D01*
X155900Y1169500D01*
X153200D01*
G01D02*
X148575D01*
G01X162800Y1215277D02*
X171723D01*
G01X165500Y1229900D02*
X162400D01*
G01X169000D02*
X165500D01*
G01X174925Y1236500D02*
Y1235825D01*
X169000Y1229900D01*
G01X177165Y88228D02*
X185700Y96763D01*
Y112900D01*
G01X189054Y138631D02*
Y134446D01*
X193575Y129925D01*
G01D02*
Y124500D01*
G01X185700Y112900D02*
X177925Y120675D01*
Y124500D01*
G01X194854Y141356D02*
X192129Y138631D01*
X189054D01*
G01X175858Y282303D02*
X177579D01*
X178811Y281071D01*
G01X175858Y279153D02*
X173480D01*
X172905Y279728D01*
G01X186100Y384000D02*
X182675Y387425D01*
X179000D01*
G01X181500Y486925D02*
Y484900D01*
X188800Y477600D01*
Y408300D01*
G01D02*
X184000Y403500D01*
G01X194900Y388000D02*
Y392600D01*
X184000Y403500D01*
G01X177165Y451614D02*
X185700Y460149D01*
Y476200D01*
G01D02*
X177500Y484400D01*
Y486925D01*
G01X181500D02*
X183850D01*
X186925Y490000D01*
G01D02*
X184500Y492425D01*
Y496000D01*
G01X189500Y512000D02*
X191575Y514075D01*
Y515500D01*
G01Y521000D02*
Y518500D01*
G01X176500Y531925D02*
X175784D01*
X173984Y530125D01*
Y528984D01*
G01X176500Y531925D02*
X179000D01*
G01X176500Y535075D02*
X179000D01*
G01X173075Y659500D02*
X173264Y659689D01*
X175811D01*
X176000Y659500D01*
G01X173075Y663500D02*
Y659500D01*
G01Y651500D02*
X175500D01*
G01X184075Y652000D02*
X187050D01*
G01X184075Y659500D02*
X187050D01*
G01X184075Y663500D02*
X187050D01*
G01X191075Y706000D02*
X193475D01*
G01X179075Y720000D02*
X181475D01*
G01X179075Y713000D02*
X181475D01*
G01X187575Y733000D02*
X192582D01*
G01X179075Y740000D02*
X181475D01*
G01X179075Y747000D02*
X181475D01*
G01X193308Y839608D02*
Y774249D01*
X178505Y759446D01*
X173800D01*
G01X193308Y839608D02*
X194400Y840700D01*
Y856000D01*
G01X185600Y852000D02*
X181425D01*
X179000Y854425D01*
G01X175858Y1009075D02*
X177579D01*
X178811Y1007843D01*
G01X175858Y1005925D02*
X173480D01*
X172905Y1006500D01*
G01X172000Y1215000D02*
X171723Y1215277D01*
G01X185441Y1235150D02*
X182741D01*
G01X186425Y1240500D02*
X183500D01*
M02*
